FILE_TYPE = MACRO_DRAWING;
SET COLOR_WIRE YELLOW;
SET COLOR_PROP ORANGE;
SET COLOR_DOT WHITE;
SET COLOR_ARC YELLOW;
SET COLOR_BODY GREEN;
SET COLOR_NOTE PURPLE;
SET PROP_DISPLAY VALUE;
SET PAGE_NUMBER P110;
FORCEADD UNIVERSAL_GND..1
(-2350 -425);
FORCEPROP 3 LASTPIN (-2350 -375) SIG_NAME GND\g
J 0
(-2340 -365);
DISPLAY 0.659574 (-2340 -365);
PAINT MONO (-2340 -365);
DISPLAY INVISIBLE (-2340 -365);
FORCEPROP 1 LAST PATH I1
J 0
(-2275 -425);
DISPLAY 0.872340 (-2275 -425);
PAINT AQUA (-2275 -425);
DISPLAY INVISIBLE (-2275 -425);
FORCEPROP 1 LAST HDL_POWER GND
J 1
(-2325 -500);
DISPLAY 0.872340 (-2325 -500);
PAINT GREEN (-2325 -500);
DISPLAY INVISIBLE (-2325 -500);
FORCEPROP 2 LAST CDS_LIB logical_power
J 0
(-2350 -425);
PAINT MONO (-2350 -425);
DISPLAY INVISIBLE (-2350 -425);
FORCEADD OFFPAGE..1
(-3475 1725);
FORCEPROP 2 LAST $XR3 113 
J 0
(-3847 1689);
DISPLAY 0.638298 (-3847 1689);
PAINT MONO (-3847 1689);
FORCEPROP 2 LAST $XR2 112 
J 0
(-3727 1689);
DISPLAY 0.638298 (-3727 1689);
PAINT MONO (-3727 1689);
FORCEPROP 2 LAST $XR1 111 
J 0
(-3847 1725);
DISPLAY 0.638298 (-3847 1725);
PAINT MONO (-3847 1725);
FORCEPROP 2 LAST $XR0 130 
J 0
(-3727 1725);
DISPLAY 0.638298 (-3727 1725);
PAINT MONO (-3727 1725);
FORCEPROP 2 LAST CDS_LIB standard
J 0
(-3475 1725);
PAINT MONO (-3475 1725);
DISPLAY INVISIBLE (-3475 1725);
FORCEPROP 1 LAST OFFPAGE TRUE
J 0
(-3150 1600);
DISPLAY 0.872340 (-3150 1600);
DISPLAY INVISIBLE (-3150 1600);
FORCEPROP 1 LAST COMMENT_BODY TRUE
J 0
(-3350 1625);
DISPLAY 0.872340 (-3350 1625);
PAINT GREEN (-3350 1625);
DISPLAY INVISIBLE (-3350 1625);
FORCEPROP 2 LAST PATH I10
J 0
(-3425 1800);
DISPLAY 1.021277 (-3425 1800);
DISPLAY INVISIBLE (-3425 1800);
FORCEADD TAP..1
(-925 3400);
FORCEPROP 3 LASTPIN (-975 3400) SIG_NAME M_G_CPU1_SA_DQ<20>
J 0
(-965 3410);
DISPLAY 0.659574 (-965 3410);
PAINT MONO (-965 3410);
DISPLAY INVISIBLE (-965 3410);
FORCEPROP 1 LASTPIN (-975 3400) BN 20
J 0
(-987 3408);
DISPLAY 0.680851 (-987 3408);
PAINT GREEN (-987 3408);
FORCEPROP 2 LAST CDS_LIB standard
J 0
(-925 3400);
PAINT MONO (-925 3400);
DISPLAY INVISIBLE (-925 3400);
FORCEPROP 1 LAST BODY_TYPE PLUMBING
J 0
(-925 3450);
DISPLAY 0.872340 (-925 3450);
PAINT GREEN (-925 3450);
DISPLAY INVISIBLE (-925 3450);
FORCEPROP 1 LAST HDL_TAP TRUE
J 0
(-600 3275);
DISPLAY 0.872340 (-600 3275);
DISPLAY INVISIBLE (-600 3275);
FORCEPROP 1 LAST PATH I100
J 0
(-927 3400);
DISPLAY 0.872340 (-927 3400);
PAINT GREEN (-927 3400);
DISPLAY INVISIBLE (-927 3400);
FORCEADD TAP..1
(-925 3450);
FORCEPROP 3 LASTPIN (-975 3450) SIG_NAME M_G_CPU1_SA_DQ<21>
J 0
(-965 3460);
DISPLAY 0.659574 (-965 3460);
PAINT MONO (-965 3460);
DISPLAY INVISIBLE (-965 3460);
FORCEPROP 1 LASTPIN (-975 3450) BN 21
J 0
(-987 3458);
DISPLAY 0.680851 (-987 3458);
PAINT GREEN (-987 3458);
FORCEPROP 2 LAST CDS_LIB standard
J 0
(-925 3450);
PAINT MONO (-925 3450);
DISPLAY INVISIBLE (-925 3450);
FORCEPROP 1 LAST BODY_TYPE PLUMBING
J 0
(-925 3500);
DISPLAY 0.872340 (-925 3500);
PAINT GREEN (-925 3500);
DISPLAY INVISIBLE (-925 3500);
FORCEPROP 1 LAST HDL_TAP TRUE
J 0
(-600 3325);
DISPLAY 0.872340 (-600 3325);
DISPLAY INVISIBLE (-600 3325);
FORCEPROP 1 LAST PATH I101
J 0
(-927 3450);
DISPLAY 0.872340 (-927 3450);
PAINT GREEN (-927 3450);
DISPLAY INVISIBLE (-927 3450);
FORCEADD TAP..1
(-925 3500);
FORCEPROP 3 LASTPIN (-975 3500) SIG_NAME M_G_CPU1_SA_DQ<22>
J 0
(-965 3510);
DISPLAY 0.659574 (-965 3510);
PAINT MONO (-965 3510);
DISPLAY INVISIBLE (-965 3510);
FORCEPROP 1 LASTPIN (-975 3500) BN 22
J 0
(-987 3508);
DISPLAY 0.680851 (-987 3508);
PAINT GREEN (-987 3508);
FORCEPROP 2 LAST CDS_LIB standard
J 0
(-925 3500);
DISPLAY INVISIBLE (-925 3500);
FORCEPROP 1 LAST BODY_TYPE PLUMBING
J 0
(-925 3550);
DISPLAY 0.872340 (-925 3550);
PAINT GREEN (-925 3550);
DISPLAY INVISIBLE (-925 3550);
FORCEPROP 1 LAST HDL_TAP TRUE
J 0
(-600 3375);
DISPLAY 0.872340 (-600 3375);
DISPLAY INVISIBLE (-600 3375);
FORCEPROP 1 LAST PATH I102
J 0
(-927 3500);
DISPLAY 0.872340 (-927 3500);
PAINT GREEN (-927 3500);
DISPLAY INVISIBLE (-927 3500);
FORCEADD TAP..1
(-925 3550);
FORCEPROP 3 LASTPIN (-975 3550) SIG_NAME M_G_CPU1_SA_DQ<23>
J 0
(-965 3560);
DISPLAY 0.659574 (-965 3560);
PAINT MONO (-965 3560);
DISPLAY INVISIBLE (-965 3560);
FORCEPROP 1 LASTPIN (-975 3550) BN 23
J 0
(-987 3558);
DISPLAY 0.680851 (-987 3558);
PAINT GREEN (-987 3558);
FORCEPROP 2 LAST CDS_LIB standard
J 0
(-925 3550);
DISPLAY INVISIBLE (-925 3550);
FORCEPROP 1 LAST BODY_TYPE PLUMBING
J 0
(-925 3600);
DISPLAY 0.872340 (-925 3600);
PAINT GREEN (-925 3600);
DISPLAY INVISIBLE (-925 3600);
FORCEPROP 1 LAST HDL_TAP TRUE
J 0
(-600 3425);
DISPLAY 0.872340 (-600 3425);
DISPLAY INVISIBLE (-600 3425);
FORCEPROP 1 LAST PATH I103
J 0
(-927 3550);
DISPLAY 0.872340 (-927 3550);
PAINT GREEN (-927 3550);
DISPLAY INVISIBLE (-927 3550);
FORCEADD TAP..1
(-925 3600);
FORCEPROP 3 LASTPIN (-975 3600) SIG_NAME M_G_CPU1_SA_DQ<24>
J 0
(-965 3610);
DISPLAY 0.659574 (-965 3610);
PAINT MONO (-965 3610);
DISPLAY INVISIBLE (-965 3610);
FORCEPROP 1 LASTPIN (-975 3600) BN 24
J 0
(-987 3608);
DISPLAY 0.680851 (-987 3608);
PAINT GREEN (-987 3608);
FORCEPROP 2 LAST CDS_LIB standard
J 0
(-925 3600);
DISPLAY INVISIBLE (-925 3600);
FORCEPROP 1 LAST BODY_TYPE PLUMBING
J 0
(-925 3650);
DISPLAY 0.872340 (-925 3650);
PAINT GREEN (-925 3650);
DISPLAY INVISIBLE (-925 3650);
FORCEPROP 1 LAST HDL_TAP TRUE
J 0
(-600 3475);
DISPLAY 0.872340 (-600 3475);
DISPLAY INVISIBLE (-600 3475);
FORCEPROP 1 LAST PATH I104
J 0
(-927 3600);
DISPLAY 0.872340 (-927 3600);
PAINT GREEN (-927 3600);
DISPLAY INVISIBLE (-927 3600);
FORCEADD TAP..1
(-925 3650);
FORCEPROP 3 LASTPIN (-975 3650) SIG_NAME M_G_CPU1_SA_DQ<25>
J 0
(-965 3660);
DISPLAY 0.659574 (-965 3660);
PAINT MONO (-965 3660);
DISPLAY INVISIBLE (-965 3660);
FORCEPROP 1 LASTPIN (-975 3650) BN 25
J 0
(-987 3658);
DISPLAY 0.680851 (-987 3658);
PAINT GREEN (-987 3658);
FORCEPROP 2 LAST CDS_LIB standard
J 0
(-925 3650);
DISPLAY INVISIBLE (-925 3650);
FORCEPROP 1 LAST BODY_TYPE PLUMBING
J 0
(-925 3700);
DISPLAY 0.872340 (-925 3700);
PAINT GREEN (-925 3700);
DISPLAY INVISIBLE (-925 3700);
FORCEPROP 1 LAST HDL_TAP TRUE
J 0
(-600 3525);
DISPLAY 0.872340 (-600 3525);
DISPLAY INVISIBLE (-600 3525);
FORCEPROP 1 LAST PATH I105
J 0
(-927 3650);
DISPLAY 0.872340 (-927 3650);
PAINT GREEN (-927 3650);
DISPLAY INVISIBLE (-927 3650);
FORCEADD OFFPAGE..1
(-3500 3975);
FORCEPROP 2 LAST $XR1 111 
J 0
(-3841 3975);
DISPLAY 0.638298 (-3841 3975);
PAINT MONO (-3841 3975);
FORCEPROP 2 LAST $XR0 57 
J 0
(-3721 3975);
DISPLAY 0.638298 (-3721 3975);
PAINT MONO (-3721 3975);
FORCEPROP 2 LAST CDS_LIB standard
J 0
(-3500 3975);
PAINT MONO (-3500 3975);
DISPLAY INVISIBLE (-3500 3975);
FORCEPROP 1 LAST OFFPAGE TRUE
J 0
(-3175 3850);
DISPLAY 0.872340 (-3175 3850);
DISPLAY INVISIBLE (-3175 3850);
FORCEPROP 1 LAST COMMENT_BODY TRUE
J 0
(-3375 3875);
DISPLAY 0.872340 (-3375 3875);
PAINT GREEN (-3375 3875);
DISPLAY INVISIBLE (-3375 3875);
FORCEPROP 2 LAST PATH I106
J 0
(-3450 4050);
DISPLAY 1.021277 (-3450 4050);
DISPLAY INVISIBLE (-3450 4050);
FORCEADD TAP..1
R 2
(-2575 3700);
FORCEPROP 3 LASTPIN (-2525 3700) SIG_NAME M_G_CPU1_SA_CA<1>
J 0
(-2515 3710);
DISPLAY 0.659574 (-2515 3710);
PAINT MONO (-2515 3710);
DISPLAY INVISIBLE (-2515 3710);
FORCEPROP 1 LASTPIN (-2525 3700) BN 1
J 2
(-2513 3708);
DISPLAY 0.680851 (-2513 3708);
PAINT GREEN (-2513 3708);
FORCEPROP 2 LAST CDS_LIB standard
J 0
(-2575 3700);
DISPLAY INVISIBLE (-2575 3700);
FORCEPROP 1 LAST BODY_TYPE PLUMBING
J 2
(-2575 3750);
DISPLAY 0.872340 (-2575 3750);
PAINT GREEN (-2575 3750);
DISPLAY INVISIBLE (-2575 3750);
FORCEPROP 1 LAST HDL_TAP TRUE
J 2
(-2900 3575);
DISPLAY 0.872340 (-2900 3575);
DISPLAY INVISIBLE (-2900 3575);
FORCEPROP 1 LAST PATH I107
J 2
(-2573 3700);
DISPLAY 0.872340 (-2573 3700);
PAINT GREEN (-2573 3700);
DISPLAY INVISIBLE (-2573 3700);
FORCEADD TAP..1
R 2
(-2575 3750);
FORCEPROP 3 LASTPIN (-2525 3750) SIG_NAME M_G_CPU1_SA_CA<2>
J 0
(-2515 3760);
DISPLAY 0.659574 (-2515 3760);
PAINT MONO (-2515 3760);
DISPLAY INVISIBLE (-2515 3760);
FORCEPROP 1 LASTPIN (-2525 3750) BN 2
J 2
(-2513 3758);
DISPLAY 0.680851 (-2513 3758);
PAINT GREEN (-2513 3758);
FORCEPROP 2 LAST CDS_LIB standard
J 0
(-2575 3750);
DISPLAY INVISIBLE (-2575 3750);
FORCEPROP 1 LAST BODY_TYPE PLUMBING
J 2
(-2575 3800);
DISPLAY 0.872340 (-2575 3800);
PAINT GREEN (-2575 3800);
DISPLAY INVISIBLE (-2575 3800);
FORCEPROP 1 LAST HDL_TAP TRUE
J 2
(-2900 3625);
DISPLAY 0.872340 (-2900 3625);
DISPLAY INVISIBLE (-2900 3625);
FORCEPROP 1 LAST PATH I108
J 2
(-2573 3750);
DISPLAY 0.872340 (-2573 3750);
PAINT GREEN (-2573 3750);
DISPLAY INVISIBLE (-2573 3750);
FORCEADD TAP..1
R 2
(-2575 3800);
FORCEPROP 3 LASTPIN (-2525 3800) SIG_NAME M_G_CPU1_SA_CA<3>
J 0
(-2515 3810);
DISPLAY 0.659574 (-2515 3810);
PAINT MONO (-2515 3810);
DISPLAY INVISIBLE (-2515 3810);
FORCEPROP 1 LASTPIN (-2525 3800) BN 3
J 2
(-2513 3808);
DISPLAY 0.680851 (-2513 3808);
PAINT GREEN (-2513 3808);
FORCEPROP 2 LAST CDS_LIB standard
J 0
(-2575 3800);
DISPLAY INVISIBLE (-2575 3800);
FORCEPROP 1 LAST BODY_TYPE PLUMBING
J 2
(-2575 3850);
DISPLAY 0.872340 (-2575 3850);
PAINT GREEN (-2575 3850);
DISPLAY INVISIBLE (-2575 3850);
FORCEPROP 1 LAST HDL_TAP TRUE
J 2
(-2900 3675);
DISPLAY 0.872340 (-2900 3675);
DISPLAY INVISIBLE (-2900 3675);
FORCEPROP 1 LAST PATH I109
J 2
(-2573 3800);
DISPLAY 0.872340 (-2573 3800);
PAINT GREEN (-2573 3800);
DISPLAY INVISIBLE (-2573 3800);
FORCEADD OFFPAGE..3
R 2
(-3500 2125);
FORCEPROP 2 LAST $XR1 111 
J 0
(-3869 2125);
DISPLAY 0.638298 (-3869 2125);
PAINT MONO (-3869 2125);
FORCEPROP 2 LAST $XR0 57 
J 0
(-3749 2125);
DISPLAY 0.638298 (-3749 2125);
PAINT MONO (-3749 2125);
FORCEPROP 2 LAST CDS_LIB standard
J 0
(-3500 2125);
PAINT MONO (-3500 2125);
DISPLAY INVISIBLE (-3500 2125);
FORCEPROP 1 LAST OFFPAGE TRUE
J 2
(-3825 2000);
DISPLAY 0.872340 (-3825 2000);
DISPLAY INVISIBLE (-3825 2000);
FORCEPROP 1 LAST COMMENT_BODY TRUE
J 2
(-3450 2025);
DISPLAY 0.872340 (-3450 2025);
PAINT GREEN (-3450 2025);
DISPLAY INVISIBLE (-3450 2025);
FORCEPROP 2 LAST PATH I11
J 0
(-3450 2200);
DISPLAY 1.021277 (-3450 2200);
DISPLAY INVISIBLE (-3450 2200);
FORCEADD TAP..1
R 2
(-2575 3900);
FORCEPROP 3 LASTPIN (-2525 3900) SIG_NAME M_G_CPU1_SA_CA<5>
J 0
(-2515 3910);
DISPLAY 0.659574 (-2515 3910);
PAINT MONO (-2515 3910);
DISPLAY INVISIBLE (-2515 3910);
FORCEPROP 1 LASTPIN (-2525 3900) BN 5
J 2
(-2513 3908);
DISPLAY 0.680851 (-2513 3908);
PAINT GREEN (-2513 3908);
FORCEPROP 2 LAST CDS_LIB standard
J 0
(-2575 3900);
DISPLAY INVISIBLE (-2575 3900);
FORCEPROP 1 LAST BODY_TYPE PLUMBING
J 2
(-2575 3950);
DISPLAY 0.872340 (-2575 3950);
PAINT GREEN (-2575 3950);
DISPLAY INVISIBLE (-2575 3950);
FORCEPROP 1 LAST HDL_TAP TRUE
J 2
(-2900 3775);
DISPLAY 0.872340 (-2900 3775);
DISPLAY INVISIBLE (-2900 3775);
FORCEPROP 1 LAST PATH I110
J 2
(-2573 3900);
DISPLAY 0.872340 (-2573 3900);
PAINT GREEN (-2573 3900);
DISPLAY INVISIBLE (-2573 3900);
FORCEADD TAP..1
R 2
(-2575 3850);
FORCEPROP 3 LASTPIN (-2525 3850) SIG_NAME M_G_CPU1_SA_CA<4>
J 0
(-2515 3860);
DISPLAY 0.659574 (-2515 3860);
PAINT MONO (-2515 3860);
DISPLAY INVISIBLE (-2515 3860);
FORCEPROP 1 LASTPIN (-2525 3850) BN 4
J 2
(-2513 3858);
DISPLAY 0.680851 (-2513 3858);
PAINT GREEN (-2513 3858);
FORCEPROP 2 LAST CDS_LIB standard
J 0
(-2575 3850);
DISPLAY INVISIBLE (-2575 3850);
FORCEPROP 1 LAST BODY_TYPE PLUMBING
J 2
(-2575 3900);
DISPLAY 0.872340 (-2575 3900);
PAINT GREEN (-2575 3900);
DISPLAY INVISIBLE (-2575 3900);
FORCEPROP 1 LAST HDL_TAP TRUE
J 2
(-2900 3725);
DISPLAY 0.872340 (-2900 3725);
DISPLAY INVISIBLE (-2900 3725);
FORCEPROP 1 LAST PATH I111
J 2
(-2573 3850);
DISPLAY 0.872340 (-2573 3850);
PAINT GREEN (-2573 3850);
DISPLAY INVISIBLE (-2573 3850);
FORCEADD TAP..1
R 2
(-2575 3950);
FORCEPROP 3 LASTPIN (-2525 3950) SIG_NAME M_G_CPU1_SA_CA<6>
J 0
(-2515 3960);
DISPLAY 0.659574 (-2515 3960);
PAINT MONO (-2515 3960);
DISPLAY INVISIBLE (-2515 3960);
FORCEPROP 1 LASTPIN (-2525 3950) BN 6
J 2
(-2513 3958);
DISPLAY 0.680851 (-2513 3958);
PAINT GREEN (-2513 3958);
FORCEPROP 2 LAST CDS_LIB standard
J 0
(-2575 3950);
DISPLAY INVISIBLE (-2575 3950);
FORCEPROP 1 LAST BODY_TYPE PLUMBING
J 2
(-2575 4000);
DISPLAY 0.872340 (-2575 4000);
PAINT GREEN (-2575 4000);
DISPLAY INVISIBLE (-2575 4000);
FORCEPROP 1 LAST HDL_TAP TRUE
J 2
(-2900 3825);
DISPLAY 0.872340 (-2900 3825);
DISPLAY INVISIBLE (-2900 3825);
FORCEPROP 1 LAST PATH I112
J 2
(-2573 3950);
DISPLAY 0.872340 (-2573 3950);
PAINT GREEN (-2573 3950);
DISPLAY INVISIBLE (-2573 3950);
FORCEADD TAP..1
(-925 3700);
FORCEPROP 3 LASTPIN (-975 3700) SIG_NAME M_G_CPU1_SA_DQ<26>
J 0
(-965 3710);
DISPLAY 0.659574 (-965 3710);
PAINT MONO (-965 3710);
DISPLAY INVISIBLE (-965 3710);
FORCEPROP 1 LASTPIN (-975 3700) BN 26
J 0
(-987 3708);
DISPLAY 0.680851 (-987 3708);
PAINT GREEN (-987 3708);
FORCEPROP 2 LAST CDS_LIB standard
J 0
(-925 3700);
DISPLAY INVISIBLE (-925 3700);
FORCEPROP 1 LAST BODY_TYPE PLUMBING
J 0
(-925 3750);
DISPLAY 0.872340 (-925 3750);
PAINT GREEN (-925 3750);
DISPLAY INVISIBLE (-925 3750);
FORCEPROP 1 LAST HDL_TAP TRUE
J 0
(-600 3575);
DISPLAY 0.872340 (-600 3575);
DISPLAY INVISIBLE (-600 3575);
FORCEPROP 1 LAST PATH I113
J 0
(-927 3700);
DISPLAY 0.872340 (-927 3700);
PAINT GREEN (-927 3700);
DISPLAY INVISIBLE (-927 3700);
FORCEADD TAP..1
(-925 3750);
FORCEPROP 3 LASTPIN (-975 3750) SIG_NAME M_G_CPU1_SA_DQ<27>
J 0
(-965 3760);
DISPLAY 0.659574 (-965 3760);
PAINT MONO (-965 3760);
DISPLAY INVISIBLE (-965 3760);
FORCEPROP 1 LASTPIN (-975 3750) BN 27
J 0
(-987 3758);
DISPLAY 0.680851 (-987 3758);
PAINT GREEN (-987 3758);
FORCEPROP 2 LAST CDS_LIB standard
J 0
(-925 3750);
DISPLAY INVISIBLE (-925 3750);
FORCEPROP 1 LAST BODY_TYPE PLUMBING
J 0
(-925 3800);
DISPLAY 0.872340 (-925 3800);
PAINT GREEN (-925 3800);
DISPLAY INVISIBLE (-925 3800);
FORCEPROP 1 LAST HDL_TAP TRUE
J 0
(-600 3625);
DISPLAY 0.872340 (-600 3625);
DISPLAY INVISIBLE (-600 3625);
FORCEPROP 1 LAST PATH I114
J 0
(-927 3750);
DISPLAY 0.872340 (-927 3750);
PAINT GREEN (-927 3750);
DISPLAY INVISIBLE (-927 3750);
FORCEADD TAP..1
(-925 3800);
FORCEPROP 3 LASTPIN (-975 3800) SIG_NAME M_G_CPU1_SA_DQ<28>
J 0
(-965 3810);
DISPLAY 0.659574 (-965 3810);
PAINT MONO (-965 3810);
DISPLAY INVISIBLE (-965 3810);
FORCEPROP 1 LASTPIN (-975 3800) BN 28
J 0
(-987 3808);
DISPLAY 0.680851 (-987 3808);
PAINT GREEN (-987 3808);
FORCEPROP 2 LAST CDS_LIB standard
J 0
(-925 3800);
DISPLAY INVISIBLE (-925 3800);
FORCEPROP 1 LAST BODY_TYPE PLUMBING
J 0
(-925 3850);
DISPLAY 0.872340 (-925 3850);
PAINT GREEN (-925 3850);
DISPLAY INVISIBLE (-925 3850);
FORCEPROP 1 LAST HDL_TAP TRUE
J 0
(-600 3675);
DISPLAY 0.872340 (-600 3675);
DISPLAY INVISIBLE (-600 3675);
FORCEPROP 1 LAST PATH I115
J 0
(-927 3800);
DISPLAY 0.872340 (-927 3800);
PAINT GREEN (-927 3800);
DISPLAY INVISIBLE (-927 3800);
FORCEADD TAP..1
(-925 3850);
FORCEPROP 3 LASTPIN (-975 3850) SIG_NAME M_G_CPU1_SA_DQ<29>
J 0
(-965 3860);
DISPLAY 0.659574 (-965 3860);
PAINT MONO (-965 3860);
DISPLAY INVISIBLE (-965 3860);
FORCEPROP 1 LASTPIN (-975 3850) BN 29
J 0
(-987 3858);
DISPLAY 0.680851 (-987 3858);
PAINT GREEN (-987 3858);
FORCEPROP 2 LAST CDS_LIB standard
J 0
(-925 3850);
DISPLAY INVISIBLE (-925 3850);
FORCEPROP 1 LAST BODY_TYPE PLUMBING
J 0
(-925 3900);
DISPLAY 0.872340 (-925 3900);
PAINT GREEN (-925 3900);
DISPLAY INVISIBLE (-925 3900);
FORCEPROP 1 LAST HDL_TAP TRUE
J 0
(-600 3725);
DISPLAY 0.872340 (-600 3725);
DISPLAY INVISIBLE (-600 3725);
FORCEPROP 1 LAST PATH I116
J 0
(-927 3850);
DISPLAY 0.872340 (-927 3850);
PAINT GREEN (-927 3850);
DISPLAY INVISIBLE (-927 3850);
FORCEADD TAP..1
(-925 3900);
FORCEPROP 3 LASTPIN (-975 3900) SIG_NAME M_G_CPU1_SA_DQ<30>
J 0
(-965 3910);
DISPLAY 0.659574 (-965 3910);
PAINT MONO (-965 3910);
DISPLAY INVISIBLE (-965 3910);
FORCEPROP 1 LASTPIN (-975 3900) BN 30
J 0
(-987 3908);
DISPLAY 0.680851 (-987 3908);
PAINT GREEN (-987 3908);
FORCEPROP 2 LAST CDS_LIB standard
J 0
(-925 3900);
DISPLAY INVISIBLE (-925 3900);
FORCEPROP 1 LAST BODY_TYPE PLUMBING
J 0
(-925 3950);
DISPLAY 0.872340 (-925 3950);
PAINT GREEN (-925 3950);
DISPLAY INVISIBLE (-925 3950);
FORCEPROP 1 LAST HDL_TAP TRUE
J 0
(-600 3775);
DISPLAY 0.872340 (-600 3775);
DISPLAY INVISIBLE (-600 3775);
FORCEPROP 1 LAST PATH I117
J 0
(-927 3900);
DISPLAY 0.872340 (-927 3900);
PAINT GREEN (-927 3900);
DISPLAY INVISIBLE (-927 3900);
FORCEADD TAP..1
(-925 3950);
FORCEPROP 3 LASTPIN (-975 3950) SIG_NAME M_G_CPU1_SA_DQ<31>
J 0
(-965 3960);
DISPLAY 0.659574 (-965 3960);
PAINT MONO (-965 3960);
DISPLAY INVISIBLE (-965 3960);
FORCEPROP 1 LASTPIN (-975 3950) BN 31
J 0
(-987 3958);
DISPLAY 0.680851 (-987 3958);
PAINT GREEN (-987 3958);
FORCEPROP 2 LAST CDS_LIB standard
J 0
(-925 3950);
DISPLAY INVISIBLE (-925 3950);
FORCEPROP 1 LAST BODY_TYPE PLUMBING
J 0
(-925 4000);
DISPLAY 0.872340 (-925 4000);
PAINT GREEN (-925 4000);
DISPLAY INVISIBLE (-925 4000);
FORCEPROP 1 LAST HDL_TAP TRUE
J 0
(-600 3825);
DISPLAY 0.872340 (-600 3825);
DISPLAY INVISIBLE (-600 3825);
FORCEPROP 1 LAST PATH I118
J 0
(-927 3950);
DISPLAY 0.872340 (-927 3950);
PAINT GREEN (-927 3950);
DISPLAY INVISIBLE (-927 3950);
FORCEADD UNIVERSAL_GND..1
(800 -300);
FORCEPROP 3 LASTPIN (800 -250) SIG_NAME GND\g
J 0
(810 -240);
DISPLAY 0.659574 (810 -240);
PAINT MONO (810 -240);
DISPLAY INVISIBLE (810 -240);
FORCEPROP 1 LAST PATH I119
J 0
(875 -300);
DISPLAY 0.872340 (875 -300);
PAINT AQUA (875 -300);
DISPLAY INVISIBLE (875 -300);
FORCEPROP 1 LAST HDL_POWER GND
J 1
(825 -375);
DISPLAY 0.872340 (825 -375);
PAINT GREEN (825 -375);
DISPLAY INVISIBLE (825 -375);
FORCEPROP 2 LAST CDS_LIB logical_power
J 0
(800 -300);
PAINT MONO (800 -300);
DISPLAY INVISIBLE (800 -300);
FORCEADD OFFPAGE..3
R 2
(-3500 2575);
FORCEPROP 2 LAST $XR1 111 
J 0
(-3869 2575);
DISPLAY 0.638298 (-3869 2575);
PAINT MONO (-3869 2575);
FORCEPROP 2 LAST $XR0 57 
J 0
(-3749 2575);
DISPLAY 0.638298 (-3749 2575);
PAINT MONO (-3749 2575);
FORCEPROP 2 LAST CDS_LIB standard
J 0
(-3500 2575);
PAINT MONO (-3500 2575);
DISPLAY INVISIBLE (-3500 2575);
FORCEPROP 1 LAST OFFPAGE TRUE
J 2
(-3825 2450);
DISPLAY 0.872340 (-3825 2450);
DISPLAY INVISIBLE (-3825 2450);
FORCEPROP 1 LAST COMMENT_BODY TRUE
J 2
(-3450 2475);
DISPLAY 0.872340 (-3450 2475);
PAINT GREEN (-3450 2475);
DISPLAY INVISIBLE (-3450 2475);
FORCEPROP 2 LAST PATH I12
J 0
(-3450 2650);
DISPLAY 1.021277 (-3450 2650);
DISPLAY INVISIBLE (-3450 2650);
FORCEADD Q_CAP..1
(800 75);
FORCEPROP 1 LAST PART_NUMBER CH5221MEB00
J 0
(850 -75);
DISPLAY 0.978723 (850 -75);
DISPLAY INVISIBLE (850 -75);
FORCEPROP 1 LAST PACK_TYPE C0402
J 0
(850 -125);
DISPLAY 0.978723 (850 -125);
FORCEPROP 1 LAST TOLERANCE 20%
J 0
(850 25);
DISPLAY 0.978723 (850 25);
FORCEPROP 1 LAST VALUE 2.2UF
J 0
(850 125);
DISPLAY 0.978723 (850 125);
FORCEPROP 1 LAST VOLTAGE 6.3V
J 0
(850 75);
DISPLAY 0.978723 (850 75);
FORCEPROP 1 LAST MATERIAL X6S
J 0
(850 -25);
DISPLAY 0.978723 (850 -25);
FORCEPROP 1 LAST $LOCATION C81
J 0
(850 175);
DISPLAY 0.978723 (850 175);
FORCEPROP 1 LASTPIN (800 175) $PN 1
J 0
(810 155);
DISPLAY 0.787234 (810 155);
FORCEPROP 1 LASTPIN (800 -25) $PN 2
J 0
(810 -45);
DISPLAY 0.787234 (810 -45);
FORCEPROP 2 LAST CDS_LIB pure_quanta
J 0
(800 75);
PAINT MONO (800 75);
DISPLAY INVISIBLE (800 75);
FORCEPROP 1 LAST PATH I120
J 0
(850 225);
DISPLAY 0.978723 (850 225);
PAINT WHITE (850 225);
DISPLAY INVISIBLE (850 225);
FORCEPROP 1 LAST $LOCATION C81
J 0
(850 275);
DISPLAY 1.021277 (850 275);
DISPLAY INVISIBLE (850 275);
FORCEPROP 2 LAST CDS_LOCATION C81
J 0
(850 275);
DISPLAY 1.021277 (850 275);
DISPLAY INVISIBLE (850 275);
FORCEPROP 2 LAST $SEC 1
J 0
(850 275);
DISPLAY 0.680851 (850 275);
PAINT MONO (850 275);
DISPLAY INVISIBLE (850 275);
FORCEPROP 2 LAST CDS_SEC 1
J 0
(850 275);
DISPLAY 1.021277 (850 275);
DISPLAY INVISIBLE (850 275);
FORCEADD VCC_CORE..1
(800 400);
FORCEPROP 3 LASTPIN (800 350) SIG_NAME P3V3_AUX\g
J 0
(810 360);
DISPLAY 0.659574 (810 360);
PAINT MONO (810 360);
DISPLAY INVISIBLE (810 360);
FORCEPROP 1 LAST HDL_POWER P3V3_AUX
J 1
(800 450);
DISPLAY 1.148936 (800 450);
PAINT GREEN (800 450);
FORCEPROP 2 LAST CDS_LIB logical_power
J 0
(800 400);
PAINT MONO (800 400);
DISPLAY INVISIBLE (800 400);
FORCEPROP 1 LAST PATH I121
J 0
(850 425);
DISPLAY 0.872340 (850 425);
PAINT AQUA (850 425);
DISPLAY INVISIBLE (850 425);
FORCEADD OFFPAGE..3
(-100 2325);
FORCEPROP 2 LAST $XR1 111 
J 0
(204 2325);
DISPLAY 0.638298 (204 2325);
PAINT MONO (204 2325);
FORCEPROP 2 LAST $XR0 57 
J 0
(114 2325);
DISPLAY 0.638298 (114 2325);
PAINT MONO (114 2325);
FORCEPROP 2 LAST CDS_LIB standard
J 2
(-100 2325);
DISPLAY INVISIBLE (-100 2325);
FORCEPROP 1 LAST OFFPAGE TRUE
J 0
(225 2200);
DISPLAY 0.872340 (225 2200);
DISPLAY INVISIBLE (225 2200);
FORCEPROP 1 LAST COMMENT_BODY TRUE
J 0
(-150 2225);
DISPLAY 0.872340 (-150 2225);
PAINT GREEN (-150 2225);
DISPLAY INVISIBLE (-150 2225);
FORCEPROP 2 LAST PATH I122
J 0
(100 2400);
DISPLAY 1.021277 (100 2400);
DISPLAY INVISIBLE (100 2400);
FORCEADD Q_CAP..1
(1800 75);
FORCEPROP 1 LAST PART_NUMBER CH6103KEA00
J 0
(1850 -75);
DISPLAY 0.978723 (1850 -75);
DISPLAY INVISIBLE (1850 -75);
FORCEPROP 1 LAST VALUE 10UF
J 0
(1850 125);
DISPLAY 0.978723 (1850 125);
FORCEPROP 1 LAST PACK_TYPE C0805
J 0
(1850 -125);
DISPLAY 0.978723 (1850 -125);
FORCEPROP 1 LAST TOLERANCE 10%
J 0
(1850 25);
DISPLAY 0.978723 (1850 25);
FORCEPROP 1 LAST VOLTAGE 16V
J 0
(1850 75);
DISPLAY 0.978723 (1850 75);
FORCEPROP 1 LAST MATERIAL X6S
J 0
(1850 -25);
DISPLAY 0.978723 (1850 -25);
FORCEPROP 1 LAST $LOCATION C82
J 0
(1850 175);
DISPLAY 0.978723 (1850 175);
FORCEPROP 1 LASTPIN (1800 175) $PN 1
J 0
(1810 155);
DISPLAY 0.787234 (1810 155);
FORCEPROP 1 LASTPIN (1800 -25) $PN 2
J 0
(1810 -45);
DISPLAY 0.787234 (1810 -45);
FORCEPROP 2 LAST CDS_LIB pure_quanta
J 0
(1800 75);
PAINT MONO (1800 75);
DISPLAY INVISIBLE (1800 75);
FORCEPROP 1 LAST PATH I124
J 0
(1850 225);
DISPLAY 0.978723 (1850 225);
PAINT WHITE (1850 225);
DISPLAY INVISIBLE (1850 225);
FORCEPROP 1 LAST $LOCATION C82
J 0
(1850 275);
DISPLAY 1.021277 (1850 275);
DISPLAY INVISIBLE (1850 275);
FORCEPROP 2 LAST CDS_LOCATION C82
J 0
(1850 275);
DISPLAY 1.021277 (1850 275);
DISPLAY INVISIBLE (1850 275);
FORCEPROP 2 LAST $SEC 1
J 0
(1850 275);
DISPLAY 0.680851 (1850 275);
PAINT MONO (1850 275);
DISPLAY INVISIBLE (1850 275);
FORCEPROP 2 LAST CDS_SEC 1
J 0
(1850 275);
DISPLAY 1.021277 (1850 275);
DISPLAY INVISIBLE (1850 275);
FORCEADD VCC_CORE..1
(1800 400);
FORCEPROP 3 LASTPIN (1800 350) SIG_NAME P12V_S3_AUX_CPU1_NVDIMM\g
J 0
(1810 360);
DISPLAY 0.659574 (1810 360);
PAINT MONO (1810 360);
DISPLAY INVISIBLE (1810 360);
FORCEPROP 1 LAST HDL_POWER P12V_S3_AUX_CPU1_NVDIMM
J 1
(1800 450);
DISPLAY 1.148936 (1800 450);
PAINT GREEN (1800 450);
FORCEPROP 2 LAST CDS_LIB logical_power
J 0
(1800 400);
PAINT MONO (1800 400);
DISPLAY INVISIBLE (1800 400);
FORCEPROP 1 LAST PATH I125
J 0
(1850 425);
DISPLAY 0.872340 (1850 425);
PAINT AQUA (1850 425);
DISPLAY INVISIBLE (1850 425);
FORCEADD Q_CAP..1
(2425 75);
FORCEPROP 1 LAST PART_NUMBER CH6103KEA00
J 0
(2475 -75);
DISPLAY 0.978723 (2475 -75);
DISPLAY INVISIBLE (2475 -75);
FORCEPROP 1 LAST TOLERANCE 10%
J 0
(2475 25);
DISPLAY 0.978723 (2475 25);
FORCEPROP 1 LAST PACK_TYPE C0805
J 0
(2475 -125);
DISPLAY 0.978723 (2475 -125);
FORCEPROP 1 LAST VOLTAGE 16V
J 0
(2475 75);
DISPLAY 0.978723 (2475 75);
FORCEPROP 1 LAST VALUE 10UF
J 0
(2475 125);
DISPLAY 0.978723 (2475 125);
FORCEPROP 1 LAST MATERIAL X6S
J 0
(2475 -25);
DISPLAY 0.978723 (2475 -25);
FORCEPROP 1 LAST $LOCATION C83
J 0
(2475 175);
DISPLAY 0.978723 (2475 175);
FORCEPROP 1 LASTPIN (2425 175) $PN 1
J 0
(2435 155);
DISPLAY 0.787234 (2435 155);
FORCEPROP 1 LASTPIN (2425 -25) $PN 2
J 0
(2435 -45);
DISPLAY 0.787234 (2435 -45);
FORCEPROP 2 LAST CDS_LIB pure_quanta
J 0
(2425 75);
PAINT MONO (2425 75);
DISPLAY INVISIBLE (2425 75);
FORCEPROP 1 LAST PATH I126
J 0
(2475 225);
DISPLAY 0.978723 (2475 225);
PAINT WHITE (2475 225);
DISPLAY INVISIBLE (2475 225);
FORCEPROP 1 LAST $LOCATION C83
J 0
(2475 275);
DISPLAY 1.021277 (2475 275);
DISPLAY INVISIBLE (2475 275);
FORCEPROP 2 LAST CDS_LOCATION C83
J 0
(2475 275);
DISPLAY 1.021277 (2475 275);
DISPLAY INVISIBLE (2475 275);
FORCEPROP 2 LAST $SEC 1
J 0
(2475 275);
DISPLAY 0.680851 (2475 275);
PAINT MONO (2475 275);
DISPLAY INVISIBLE (2475 275);
FORCEPROP 2 LAST CDS_SEC 1
J 0
(2475 275);
DISPLAY 1.021277 (2475 275);
DISPLAY INVISIBLE (2475 275);
FORCEADD UNIVERSAL_GND..1
(2425 -300);
FORCEPROP 3 LASTPIN (2425 -250) SIG_NAME GND\g
J 0
(2435 -240);
DISPLAY 0.659574 (2435 -240);
PAINT MONO (2435 -240);
DISPLAY INVISIBLE (2435 -240);
FORCEPROP 1 LAST PATH I127
J 0
(2500 -300);
DISPLAY 0.872340 (2500 -300);
PAINT AQUA (2500 -300);
DISPLAY INVISIBLE (2500 -300);
FORCEPROP 1 LAST HDL_POWER GND
J 1
(2450 -375);
DISPLAY 0.872340 (2450 -375);
PAINT GREEN (2450 -375);
DISPLAY INVISIBLE (2450 -375);
FORCEPROP 2 LAST CDS_LIB logical_power
J 0
(2425 -300);
PAINT MONO (2425 -300);
DISPLAY INVISIBLE (2425 -300);
FORCEADD UNIVERSAL_GND..1
(3500 250);
FORCEPROP 3 LASTPIN (3500 300) SIG_NAME GND\g
J 0
(3510 310);
DISPLAY 0.659574 (3510 310);
PAINT MONO (3510 310);
DISPLAY INVISIBLE (3510 310);
FORCEPROP 1 LAST PATH I128
J 0
(3575 250);
DISPLAY 0.872340 (3575 250);
PAINT AQUA (3575 250);
DISPLAY INVISIBLE (3575 250);
FORCEPROP 1 LAST HDL_POWER GND
J 1
(3525 175);
DISPLAY 0.872340 (3525 175);
PAINT GREEN (3525 175);
DISPLAY INVISIBLE (3525 175);
FORCEPROP 2 LAST CDS_LIB logical_power
J 0
(3500 250);
PAINT MONO (3500 250);
DISPLAY INVISIBLE (3500 250);
FORCEADD TAP..1
(1825 2000);
FORCEPROP 3 LASTPIN (1775 2000) SIG_NAME M_G_CPU1_SB_DQS_DP<0>
J 0
(1785 2010);
DISPLAY 0.659574 (1785 2010);
PAINT MONO (1785 2010);
DISPLAY INVISIBLE (1785 2010);
FORCEPROP 1 LASTPIN (1775 2000) BN 0
J 0
(1763 2008);
DISPLAY 0.680851 (1763 2008);
PAINT GREEN (1763 2008);
FORCEPROP 2 LAST CDS_LIB standard
J 0
(1825 2000);
PAINT MONO (1825 2000);
DISPLAY INVISIBLE (1825 2000);
FORCEPROP 1 LAST BODY_TYPE PLUMBING
J 0
(1825 2050);
DISPLAY 0.872340 (1825 2050);
PAINT GREEN (1825 2050);
DISPLAY INVISIBLE (1825 2050);
FORCEPROP 1 LAST HDL_TAP TRUE
J 0
(2150 1875);
DISPLAY 0.872340 (2150 1875);
DISPLAY INVISIBLE (2150 1875);
FORCEPROP 1 LAST PATH I129
J 0
(1823 2000);
DISPLAY 0.872340 (1823 2000);
PAINT GREEN (1823 2000);
DISPLAY INVISIBLE (1823 2000);
FORCEADD OFFPAGE..1
(-3500 2650);
FORCEPROP 2 LAST $XR0 57 
J 0
(-3721 2650);
DISPLAY 0.638298 (-3721 2650);
PAINT MONO (-3721 2650);
FORCEPROP 2 LAST CDS_LIB standard
J 0
(-3500 2650);
PAINT MONO (-3500 2650);
DISPLAY INVISIBLE (-3500 2650);
FORCEPROP 1 LAST OFFPAGE TRUE
J 0
(-3175 2525);
DISPLAY 0.872340 (-3175 2525);
DISPLAY INVISIBLE (-3175 2525);
FORCEPROP 1 LAST COMMENT_BODY TRUE
J 0
(-3375 2550);
DISPLAY 0.872340 (-3375 2550);
PAINT GREEN (-3375 2550);
DISPLAY INVISIBLE (-3375 2550);
FORCEPROP 2 LAST PATH I13
J 0
(-3450 2725);
DISPLAY 1.021277 (-3450 2725);
DISPLAY INVISIBLE (-3450 2725);
FORCEADD TAP..1
(1825 2100);
FORCEPROP 3 LASTPIN (1775 2100) SIG_NAME M_G_CPU1_SB_DQS_DP<1>
J 0
(1785 2110);
DISPLAY 0.659574 (1785 2110);
PAINT MONO (1785 2110);
DISPLAY INVISIBLE (1785 2110);
FORCEPROP 1 LASTPIN (1775 2100) BN 1
J 0
(1763 2108);
DISPLAY 0.680851 (1763 2108);
PAINT GREEN (1763 2108);
FORCEPROP 2 LAST CDS_LIB standard
J 0
(1825 2100);
DISPLAY INVISIBLE (1825 2100);
FORCEPROP 1 LAST BODY_TYPE PLUMBING
J 0
(1825 2150);
DISPLAY 0.872340 (1825 2150);
PAINT GREEN (1825 2150);
DISPLAY INVISIBLE (1825 2150);
FORCEPROP 1 LAST HDL_TAP TRUE
J 0
(2150 1975);
DISPLAY 0.872340 (2150 1975);
DISPLAY INVISIBLE (2150 1975);
FORCEPROP 1 LAST PATH I130
J 0
(1823 2100);
DISPLAY 0.872340 (1823 2100);
PAINT GREEN (1823 2100);
DISPLAY INVISIBLE (1823 2100);
FORCEADD TAP..1
(2000 1950);
FORCEPROP 3 LASTPIN (1950 1950) SIG_NAME M_G_CPU1_SB_DQS_DN<0>
J 0
(1960 1960);
DISPLAY 0.659574 (1960 1960);
PAINT MONO (1960 1960);
DISPLAY INVISIBLE (1960 1960);
FORCEPROP 1 LASTPIN (1950 1950) BN 0
J 0
(1938 1958);
DISPLAY 0.680851 (1938 1958);
PAINT GREEN (1938 1958);
FORCEPROP 2 LAST CDS_LIB standard
J 0
(2000 1950);
PAINT MONO (2000 1950);
DISPLAY INVISIBLE (2000 1950);
FORCEPROP 1 LAST BODY_TYPE PLUMBING
J 0
(2000 2000);
DISPLAY 0.872340 (2000 2000);
PAINT GREEN (2000 2000);
DISPLAY INVISIBLE (2000 2000);
FORCEPROP 1 LAST HDL_TAP TRUE
J 0
(2325 1825);
DISPLAY 0.872340 (2325 1825);
DISPLAY INVISIBLE (2325 1825);
FORCEPROP 1 LAST PATH I131
J 0
(1998 1950);
DISPLAY 0.872340 (1998 1950);
PAINT GREEN (1998 1950);
DISPLAY INVISIBLE (1998 1950);
FORCEADD TAP..1
(2000 2050);
FORCEPROP 3 LASTPIN (1950 2050) SIG_NAME M_G_CPU1_SB_DQS_DN<1>
J 0
(1960 2060);
DISPLAY 0.659574 (1960 2060);
PAINT MONO (1960 2060);
DISPLAY INVISIBLE (1960 2060);
FORCEPROP 1 LASTPIN (1950 2050) BN 1
J 0
(1938 2058);
DISPLAY 0.680851 (1938 2058);
PAINT GREEN (1938 2058);
FORCEPROP 2 LAST CDS_LIB standard
J 0
(2000 2050);
DISPLAY INVISIBLE (2000 2050);
FORCEPROP 1 LAST BODY_TYPE PLUMBING
J 0
(2000 2100);
DISPLAY 0.872340 (2000 2100);
PAINT GREEN (2000 2100);
DISPLAY INVISIBLE (2000 2100);
FORCEPROP 1 LAST HDL_TAP TRUE
J 0
(2325 1925);
DISPLAY 0.872340 (2325 1925);
DISPLAY INVISIBLE (2325 1925);
FORCEPROP 1 LAST PATH I132
J 0
(1998 2050);
DISPLAY 0.872340 (1998 2050);
PAINT GREEN (1998 2050);
DISPLAY INVISIBLE (1998 2050);
FORCEADD TAP..1
(2000 2150);
FORCEPROP 3 LASTPIN (1950 2150) SIG_NAME M_G_CPU1_SB_DQS_DN<2>
J 0
(1960 2160);
DISPLAY 0.659574 (1960 2160);
PAINT MONO (1960 2160);
DISPLAY INVISIBLE (1960 2160);
FORCEPROP 1 LASTPIN (1950 2150) BN 2
J 0
(1938 2158);
DISPLAY 0.680851 (1938 2158);
PAINT GREEN (1938 2158);
FORCEPROP 2 LAST CDS_LIB standard
J 0
(2000 2150);
DISPLAY INVISIBLE (2000 2150);
FORCEPROP 1 LAST BODY_TYPE PLUMBING
J 0
(2000 2200);
DISPLAY 0.872340 (2000 2200);
PAINT GREEN (2000 2200);
DISPLAY INVISIBLE (2000 2200);
FORCEPROP 1 LAST HDL_TAP TRUE
J 0
(2325 2025);
DISPLAY 0.872340 (2325 2025);
DISPLAY INVISIBLE (2325 2025);
FORCEPROP 1 LAST PATH I133
J 0
(1998 2150);
DISPLAY 0.872340 (1998 2150);
PAINT GREEN (1998 2150);
DISPLAY INVISIBLE (1998 2150);
FORCEADD TAP..1
(1825 2200);
FORCEPROP 3 LASTPIN (1775 2200) SIG_NAME M_G_CPU1_SB_DQS_DP<2>
J 0
(1785 2210);
DISPLAY 0.659574 (1785 2210);
PAINT MONO (1785 2210);
DISPLAY INVISIBLE (1785 2210);
FORCEPROP 1 LASTPIN (1775 2200) BN 2
J 0
(1763 2208);
DISPLAY 0.680851 (1763 2208);
PAINT GREEN (1763 2208);
FORCEPROP 2 LAST CDS_LIB standard
J 0
(1825 2200);
DISPLAY INVISIBLE (1825 2200);
FORCEPROP 1 LAST BODY_TYPE PLUMBING
J 0
(1825 2250);
DISPLAY 0.872340 (1825 2250);
PAINT GREEN (1825 2250);
DISPLAY INVISIBLE (1825 2250);
FORCEPROP 1 LAST HDL_TAP TRUE
J 0
(2150 2075);
DISPLAY 0.872340 (2150 2075);
DISPLAY INVISIBLE (2150 2075);
FORCEPROP 1 LAST PATH I134
J 0
(1823 2200);
DISPLAY 0.872340 (1823 2200);
PAINT GREEN (1823 2200);
DISPLAY INVISIBLE (1823 2200);
FORCEADD TAP..1
(1825 2400);
FORCEPROP 3 LASTPIN (1775 2400) SIG_NAME M_G_CPU1_SB_DQS_DP<4>
J 0
(1785 2410);
DISPLAY 0.659574 (1785 2410);
PAINT MONO (1785 2410);
DISPLAY INVISIBLE (1785 2410);
FORCEPROP 1 LASTPIN (1775 2400) BN 4
J 0
(1763 2408);
DISPLAY 0.680851 (1763 2408);
PAINT GREEN (1763 2408);
FORCEPROP 2 LAST CDS_LIB standard
J 0
(1825 2400);
PAINT MONO (1825 2400);
DISPLAY INVISIBLE (1825 2400);
FORCEPROP 1 LAST BODY_TYPE PLUMBING
J 0
(1825 2450);
DISPLAY 0.872340 (1825 2450);
PAINT GREEN (1825 2450);
DISPLAY INVISIBLE (1825 2450);
FORCEPROP 1 LAST HDL_TAP TRUE
J 0
(2150 2275);
DISPLAY 0.872340 (2150 2275);
DISPLAY INVISIBLE (2150 2275);
FORCEPROP 1 LAST PATH I135
J 0
(1823 2400);
DISPLAY 0.872340 (1823 2400);
PAINT GREEN (1823 2400);
DISPLAY INVISIBLE (1823 2400);
FORCEADD TAP..1
(1825 2300);
FORCEPROP 3 LASTPIN (1775 2300) SIG_NAME M_G_CPU1_SB_DQS_DP<3>
J 0
(1785 2310);
DISPLAY 0.659574 (1785 2310);
PAINT MONO (1785 2310);
DISPLAY INVISIBLE (1785 2310);
FORCEPROP 1 LASTPIN (1775 2300) BN 3
J 0
(1763 2308);
DISPLAY 0.680851 (1763 2308);
PAINT GREEN (1763 2308);
FORCEPROP 2 LAST CDS_LIB standard
J 0
(1825 2300);
PAINT MONO (1825 2300);
DISPLAY INVISIBLE (1825 2300);
FORCEPROP 1 LAST BODY_TYPE PLUMBING
J 0
(1825 2350);
DISPLAY 0.872340 (1825 2350);
PAINT GREEN (1825 2350);
DISPLAY INVISIBLE (1825 2350);
FORCEPROP 1 LAST HDL_TAP TRUE
J 0
(2150 2175);
DISPLAY 0.872340 (2150 2175);
DISPLAY INVISIBLE (2150 2175);
FORCEPROP 1 LAST PATH I136
J 0
(1823 2300);
DISPLAY 0.872340 (1823 2300);
PAINT GREEN (1823 2300);
DISPLAY INVISIBLE (1823 2300);
FORCEADD TAP..1
(2000 2350);
FORCEPROP 3 LASTPIN (1950 2350) SIG_NAME M_G_CPU1_SB_DQS_DN<4>
J 0
(1960 2360);
DISPLAY 0.659574 (1960 2360);
PAINT MONO (1960 2360);
DISPLAY INVISIBLE (1960 2360);
FORCEPROP 1 LASTPIN (1950 2350) BN 4
J 0
(1938 2358);
DISPLAY 0.680851 (1938 2358);
PAINT GREEN (1938 2358);
FORCEPROP 2 LAST CDS_LIB standard
J 0
(2000 2350);
PAINT MONO (2000 2350);
DISPLAY INVISIBLE (2000 2350);
FORCEPROP 1 LAST BODY_TYPE PLUMBING
J 0
(2000 2400);
DISPLAY 0.872340 (2000 2400);
PAINT GREEN (2000 2400);
DISPLAY INVISIBLE (2000 2400);
FORCEPROP 1 LAST HDL_TAP TRUE
J 0
(2325 2225);
DISPLAY 0.872340 (2325 2225);
DISPLAY INVISIBLE (2325 2225);
FORCEPROP 1 LAST PATH I137
J 0
(1998 2350);
DISPLAY 0.872340 (1998 2350);
PAINT GREEN (1998 2350);
DISPLAY INVISIBLE (1998 2350);
FORCEADD TAP..1
(2000 2250);
FORCEPROP 3 LASTPIN (1950 2250) SIG_NAME M_G_CPU1_SB_DQS_DN<3>
J 0
(1960 2260);
DISPLAY 0.659574 (1960 2260);
PAINT MONO (1960 2260);
DISPLAY INVISIBLE (1960 2260);
FORCEPROP 1 LASTPIN (1950 2250) BN 3
J 0
(1938 2258);
DISPLAY 0.680851 (1938 2258);
PAINT GREEN (1938 2258);
FORCEPROP 2 LAST CDS_LIB standard
J 0
(2000 2250);
PAINT MONO (2000 2250);
DISPLAY INVISIBLE (2000 2250);
FORCEPROP 1 LAST BODY_TYPE PLUMBING
J 0
(2000 2300);
DISPLAY 0.872340 (2000 2300);
PAINT GREEN (2000 2300);
DISPLAY INVISIBLE (2000 2300);
FORCEPROP 1 LAST HDL_TAP TRUE
J 0
(2325 2125);
DISPLAY 0.872340 (2325 2125);
DISPLAY INVISIBLE (2325 2125);
FORCEPROP 1 LAST PATH I138
J 0
(1998 2250);
DISPLAY 0.872340 (1998 2250);
PAINT GREEN (1998 2250);
DISPLAY INVISIBLE (1998 2250);
FORCEADD TAP..1
(1825 2500);
FORCEPROP 3 LASTPIN (1775 2500) SIG_NAME M_G_CPU1_SB_DQS_DP<5>
J 0
(1785 2510);
DISPLAY 0.659574 (1785 2510);
PAINT MONO (1785 2510);
DISPLAY INVISIBLE (1785 2510);
FORCEPROP 1 LASTPIN (1775 2500) BN 5
J 0
(1763 2508);
DISPLAY 0.680851 (1763 2508);
PAINT GREEN (1763 2508);
FORCEPROP 2 LAST CDS_LIB standard
J 0
(1825 2500);
DISPLAY INVISIBLE (1825 2500);
FORCEPROP 1 LAST BODY_TYPE PLUMBING
J 0
(1825 2550);
DISPLAY 0.872340 (1825 2550);
PAINT GREEN (1825 2550);
DISPLAY INVISIBLE (1825 2550);
FORCEPROP 1 LAST HDL_TAP TRUE
J 0
(2150 2375);
DISPLAY 0.872340 (2150 2375);
DISPLAY INVISIBLE (2150 2375);
FORCEPROP 1 LAST PATH I139
J 0
(1823 2500);
DISPLAY 0.872340 (1823 2500);
PAINT GREEN (1823 2500);
DISPLAY INVISIBLE (1823 2500);
FORCEADD OFFPAGE..1
(-3500 2700);
FORCEPROP 2 LAST $XR0 57 
J 0
(-3721 2700);
DISPLAY 0.638298 (-3721 2700);
PAINT MONO (-3721 2700);
FORCEPROP 2 LAST CDS_LIB standard
J 0
(-3500 2700);
PAINT MONO (-3500 2700);
DISPLAY INVISIBLE (-3500 2700);
FORCEPROP 1 LAST OFFPAGE TRUE
J 0
(-3175 2575);
DISPLAY 0.872340 (-3175 2575);
DISPLAY INVISIBLE (-3175 2575);
FORCEPROP 1 LAST COMMENT_BODY TRUE
J 0
(-3375 2600);
DISPLAY 0.872340 (-3375 2600);
PAINT GREEN (-3375 2600);
DISPLAY INVISIBLE (-3375 2600);
FORCEPROP 2 LAST PATH I14
J 0
(-3450 2775);
DISPLAY 1.021277 (-3450 2775);
DISPLAY INVISIBLE (-3450 2775);
FORCEADD TAP..1
(1825 2600);
FORCEPROP 3 LASTPIN (1775 2600) SIG_NAME M_G_CPU1_SB_DQS_DP<6>
J 0
(1785 2610);
DISPLAY 0.659574 (1785 2610);
PAINT MONO (1785 2610);
DISPLAY INVISIBLE (1785 2610);
FORCEPROP 1 LASTPIN (1775 2600) BN 6
J 0
(1763 2608);
DISPLAY 0.680851 (1763 2608);
PAINT GREEN (1763 2608);
FORCEPROP 2 LAST CDS_LIB standard
J 0
(1825 2600);
DISPLAY INVISIBLE (1825 2600);
FORCEPROP 1 LAST BODY_TYPE PLUMBING
J 0
(1825 2650);
DISPLAY 0.872340 (1825 2650);
PAINT GREEN (1825 2650);
DISPLAY INVISIBLE (1825 2650);
FORCEPROP 1 LAST HDL_TAP TRUE
J 0
(2150 2475);
DISPLAY 0.872340 (2150 2475);
DISPLAY INVISIBLE (2150 2475);
FORCEPROP 1 LAST PATH I140
J 0
(1823 2600);
DISPLAY 0.872340 (1823 2600);
PAINT GREEN (1823 2600);
DISPLAY INVISIBLE (1823 2600);
FORCEADD TAP..1
(2000 2450);
FORCEPROP 3 LASTPIN (1950 2450) SIG_NAME M_G_CPU1_SB_DQS_DN<5>
J 0
(1960 2460);
DISPLAY 0.659574 (1960 2460);
PAINT MONO (1960 2460);
DISPLAY INVISIBLE (1960 2460);
FORCEPROP 1 LASTPIN (1950 2450) BN 5
J 0
(1938 2458);
DISPLAY 0.680851 (1938 2458);
PAINT GREEN (1938 2458);
FORCEPROP 2 LAST CDS_LIB standard
J 0
(2000 2450);
DISPLAY INVISIBLE (2000 2450);
FORCEPROP 1 LAST BODY_TYPE PLUMBING
J 0
(2000 2500);
DISPLAY 0.872340 (2000 2500);
PAINT GREEN (2000 2500);
DISPLAY INVISIBLE (2000 2500);
FORCEPROP 1 LAST HDL_TAP TRUE
J 0
(2325 2325);
DISPLAY 0.872340 (2325 2325);
DISPLAY INVISIBLE (2325 2325);
FORCEPROP 1 LAST PATH I141
J 0
(1998 2450);
DISPLAY 0.872340 (1998 2450);
PAINT GREEN (1998 2450);
DISPLAY INVISIBLE (1998 2450);
FORCEADD TAP..1
(2000 2650);
FORCEPROP 3 LASTPIN (1950 2650) SIG_NAME M_G_CPU1_SB_DQS_DN<7>
J 0
(1960 2660);
DISPLAY 0.659574 (1960 2660);
PAINT MONO (1960 2660);
DISPLAY INVISIBLE (1960 2660);
FORCEPROP 1 LASTPIN (1950 2650) BN 7
J 0
(1938 2658);
DISPLAY 0.680851 (1938 2658);
PAINT GREEN (1938 2658);
FORCEPROP 2 LAST CDS_LIB standard
J 0
(2000 2650);
DISPLAY INVISIBLE (2000 2650);
FORCEPROP 1 LAST BODY_TYPE PLUMBING
J 0
(2000 2700);
DISPLAY 0.872340 (2000 2700);
PAINT GREEN (2000 2700);
DISPLAY INVISIBLE (2000 2700);
FORCEPROP 1 LAST HDL_TAP TRUE
J 0
(2325 2525);
DISPLAY 0.872340 (2325 2525);
DISPLAY INVISIBLE (2325 2525);
FORCEPROP 1 LAST PATH I142
J 0
(1998 2650);
DISPLAY 0.872340 (1998 2650);
PAINT GREEN (1998 2650);
DISPLAY INVISIBLE (1998 2650);
FORCEADD TAP..1
(2000 2550);
FORCEPROP 3 LASTPIN (1950 2550) SIG_NAME M_G_CPU1_SB_DQS_DN<6>
J 0
(1960 2560);
DISPLAY 0.659574 (1960 2560);
PAINT MONO (1960 2560);
DISPLAY INVISIBLE (1960 2560);
FORCEPROP 1 LASTPIN (1950 2550) BN 6
J 0
(1938 2558);
DISPLAY 0.680851 (1938 2558);
PAINT GREEN (1938 2558);
FORCEPROP 2 LAST CDS_LIB standard
J 0
(2000 2550);
DISPLAY INVISIBLE (2000 2550);
FORCEPROP 1 LAST BODY_TYPE PLUMBING
J 0
(2000 2600);
DISPLAY 0.872340 (2000 2600);
PAINT GREEN (2000 2600);
DISPLAY INVISIBLE (2000 2600);
FORCEPROP 1 LAST HDL_TAP TRUE
J 0
(2325 2425);
DISPLAY 0.872340 (2325 2425);
DISPLAY INVISIBLE (2325 2425);
FORCEPROP 1 LAST PATH I143
J 0
(1998 2550);
DISPLAY 0.872340 (1998 2550);
PAINT GREEN (1998 2550);
DISPLAY INVISIBLE (1998 2550);
FORCEADD TAP..1
(1825 2700);
FORCEPROP 3 LASTPIN (1775 2700) SIG_NAME M_G_CPU1_SB_DQS_DP<7>
J 0
(1785 2710);
DISPLAY 0.659574 (1785 2710);
PAINT MONO (1785 2710);
DISPLAY INVISIBLE (1785 2710);
FORCEPROP 1 LASTPIN (1775 2700) BN 7
J 0
(1763 2708);
DISPLAY 0.680851 (1763 2708);
PAINT GREEN (1763 2708);
FORCEPROP 2 LAST CDS_LIB standard
J 0
(1825 2700);
DISPLAY INVISIBLE (1825 2700);
FORCEPROP 1 LAST BODY_TYPE PLUMBING
J 0
(1825 2750);
DISPLAY 0.872340 (1825 2750);
PAINT GREEN (1825 2750);
DISPLAY INVISIBLE (1825 2750);
FORCEPROP 1 LAST HDL_TAP TRUE
J 0
(2150 2575);
DISPLAY 0.872340 (2150 2575);
DISPLAY INVISIBLE (2150 2575);
FORCEPROP 1 LAST PATH I144
J 0
(1823 2700);
DISPLAY 0.872340 (1823 2700);
PAINT GREEN (1823 2700);
DISPLAY INVISIBLE (1823 2700);
FORCEADD TAP..1
(1825 2800);
FORCEPROP 3 LASTPIN (1775 2800) SIG_NAME M_G_CPU1_SB_DQS_DP<8>
J 0
(1785 2810);
DISPLAY 0.659574 (1785 2810);
PAINT MONO (1785 2810);
DISPLAY INVISIBLE (1785 2810);
FORCEPROP 1 LASTPIN (1775 2800) BN 8
J 0
(1763 2808);
DISPLAY 0.680851 (1763 2808);
PAINT GREEN (1763 2808);
FORCEPROP 2 LAST CDS_LIB standard
J 0
(1825 2800);
DISPLAY INVISIBLE (1825 2800);
FORCEPROP 1 LAST BODY_TYPE PLUMBING
J 0
(1825 2850);
DISPLAY 0.872340 (1825 2850);
PAINT GREEN (1825 2850);
DISPLAY INVISIBLE (1825 2850);
FORCEPROP 1 LAST HDL_TAP TRUE
J 0
(2150 2675);
DISPLAY 0.872340 (2150 2675);
DISPLAY INVISIBLE (2150 2675);
FORCEPROP 1 LAST PATH I145
J 0
(1823 2800);
DISPLAY 0.872340 (1823 2800);
PAINT GREEN (1823 2800);
DISPLAY INVISIBLE (1823 2800);
FORCEADD TAP..1
(1825 2900);
FORCEPROP 3 LASTPIN (1775 2900) SIG_NAME M_G_CPU1_SB_DQS_DP<9>
J 0
(1785 2910);
DISPLAY 0.659574 (1785 2910);
PAINT MONO (1785 2910);
DISPLAY INVISIBLE (1785 2910);
FORCEPROP 1 LASTPIN (1775 2900) BN 9
J 0
(1763 2908);
DISPLAY 0.680851 (1763 2908);
PAINT GREEN (1763 2908);
FORCEPROP 2 LAST CDS_LIB standard
J 0
(1825 2900);
DISPLAY INVISIBLE (1825 2900);
FORCEPROP 1 LAST BODY_TYPE PLUMBING
J 0
(1825 2950);
DISPLAY 0.872340 (1825 2950);
PAINT GREEN (1825 2950);
DISPLAY INVISIBLE (1825 2950);
FORCEPROP 1 LAST HDL_TAP TRUE
J 0
(2150 2775);
DISPLAY 0.872340 (2150 2775);
DISPLAY INVISIBLE (2150 2775);
FORCEPROP 1 LAST PATH I146
J 0
(1823 2900);
DISPLAY 0.872340 (1823 2900);
PAINT GREEN (1823 2900);
DISPLAY INVISIBLE (1823 2900);
FORCEADD TAP..1
(2000 2750);
FORCEPROP 3 LASTPIN (1950 2750) SIG_NAME M_G_CPU1_SB_DQS_DN<8>
J 0
(1960 2760);
DISPLAY 0.659574 (1960 2760);
PAINT MONO (1960 2760);
DISPLAY INVISIBLE (1960 2760);
FORCEPROP 1 LASTPIN (1950 2750) BN 8
J 0
(1938 2758);
DISPLAY 0.680851 (1938 2758);
PAINT GREEN (1938 2758);
FORCEPROP 2 LAST CDS_LIB standard
J 0
(2000 2750);
DISPLAY INVISIBLE (2000 2750);
FORCEPROP 1 LAST BODY_TYPE PLUMBING
J 0
(2000 2800);
DISPLAY 0.872340 (2000 2800);
PAINT GREEN (2000 2800);
DISPLAY INVISIBLE (2000 2800);
FORCEPROP 1 LAST HDL_TAP TRUE
J 0
(2325 2625);
DISPLAY 0.872340 (2325 2625);
DISPLAY INVISIBLE (2325 2625);
FORCEPROP 1 LAST PATH I147
J 0
(1998 2750);
DISPLAY 0.872340 (1998 2750);
PAINT GREEN (1998 2750);
DISPLAY INVISIBLE (1998 2750);
FORCEADD TAP..1
(2000 2850);
FORCEPROP 3 LASTPIN (1950 2850) SIG_NAME M_G_CPU1_SB_DQS_DN<9>
J 0
(1960 2860);
DISPLAY 0.659574 (1960 2860);
PAINT MONO (1960 2860);
DISPLAY INVISIBLE (1960 2860);
FORCEPROP 1 LASTPIN (1950 2850) BN 9
J 0
(1938 2858);
DISPLAY 0.680851 (1938 2858);
PAINT GREEN (1938 2858);
FORCEPROP 2 LAST CDS_LIB standard
J 0
(2000 2850);
DISPLAY INVISIBLE (2000 2850);
FORCEPROP 1 LAST BODY_TYPE PLUMBING
J 0
(2000 2900);
DISPLAY 0.872340 (2000 2900);
PAINT GREEN (2000 2900);
DISPLAY INVISIBLE (2000 2900);
FORCEPROP 1 LAST HDL_TAP TRUE
J 0
(2325 2725);
DISPLAY 0.872340 (2325 2725);
DISPLAY INVISIBLE (2325 2725);
FORCEPROP 1 LAST PATH I148
J 0
(1998 2850);
DISPLAY 0.872340 (1998 2850);
PAINT GREEN (1998 2850);
DISPLAY INVISIBLE (1998 2850);
FORCEADD TAP..1
(1825 3150);
FORCEPROP 3 LASTPIN (1775 3150) SIG_NAME M_G_CPU1_SA_DQS_DP<1>
J 0
(1785 3160);
DISPLAY 0.659574 (1785 3160);
PAINT MONO (1785 3160);
DISPLAY INVISIBLE (1785 3160);
FORCEPROP 1 LASTPIN (1775 3150) BN 1
J 0
(1763 3158);
DISPLAY 0.680851 (1763 3158);
PAINT GREEN (1763 3158);
FORCEPROP 2 LAST CDS_LIB standard
J 0
(1825 3150);
DISPLAY INVISIBLE (1825 3150);
FORCEPROP 1 LAST BODY_TYPE PLUMBING
J 0
(1825 3200);
DISPLAY 0.872340 (1825 3200);
PAINT GREEN (1825 3200);
DISPLAY INVISIBLE (1825 3200);
FORCEPROP 1 LAST HDL_TAP TRUE
J 0
(2150 3025);
DISPLAY 0.872340 (2150 3025);
DISPLAY INVISIBLE (2150 3025);
FORCEPROP 1 LAST PATH I149
J 0
(1823 3150);
DISPLAY 0.872340 (1823 3150);
PAINT GREEN (1823 3150);
DISPLAY INVISIBLE (1823 3150);
FORCEADD OFFPAGE..1
(-3500 2850);
FORCEPROP 2 LAST $XR0 57 
J 0
(-3721 2850);
DISPLAY 0.638298 (-3721 2850);
PAINT MONO (-3721 2850);
FORCEPROP 2 LAST CDS_LIB standard
J 0
(-3500 2850);
PAINT MONO (-3500 2850);
DISPLAY INVISIBLE (-3500 2850);
FORCEPROP 1 LAST OFFPAGE TRUE
J 0
(-3175 2725);
DISPLAY 0.872340 (-3175 2725);
DISPLAY INVISIBLE (-3175 2725);
FORCEPROP 1 LAST COMMENT_BODY TRUE
J 0
(-3375 2750);
DISPLAY 0.872340 (-3375 2750);
PAINT GREEN (-3375 2750);
DISPLAY INVISIBLE (-3375 2750);
FORCEPROP 2 LAST PATH I15
J 0
(-3450 2925);
DISPLAY 1.021277 (-3450 2925);
DISPLAY INVISIBLE (-3450 2925);
FORCEADD TAP..1
(1825 3050);
FORCEPROP 3 LASTPIN (1775 3050) SIG_NAME M_G_CPU1_SA_DQS_DP<0>
J 0
(1785 3060);
DISPLAY 0.659574 (1785 3060);
PAINT MONO (1785 3060);
DISPLAY INVISIBLE (1785 3060);
FORCEPROP 1 LASTPIN (1775 3050) BN 0
J 0
(1763 3058);
DISPLAY 0.680851 (1763 3058);
PAINT GREEN (1763 3058);
FORCEPROP 2 LAST CDS_LIB standard
J 0
(1825 3050);
PAINT MONO (1825 3050);
DISPLAY INVISIBLE (1825 3050);
FORCEPROP 1 LAST BODY_TYPE PLUMBING
J 0
(1825 3100);
DISPLAY 0.872340 (1825 3100);
PAINT GREEN (1825 3100);
DISPLAY INVISIBLE (1825 3100);
FORCEPROP 1 LAST HDL_TAP TRUE
J 0
(2150 2925);
DISPLAY 0.872340 (2150 2925);
DISPLAY INVISIBLE (2150 2925);
FORCEPROP 1 LAST PATH I150
J 0
(1823 3050);
DISPLAY 0.872340 (1823 3050);
PAINT GREEN (1823 3050);
DISPLAY INVISIBLE (1823 3050);
FORCEADD TAP..1
(2000 3100);
FORCEPROP 3 LASTPIN (1950 3100) SIG_NAME M_G_CPU1_SA_DQS_DN<1>
J 0
(1960 3110);
DISPLAY 0.659574 (1960 3110);
PAINT MONO (1960 3110);
DISPLAY INVISIBLE (1960 3110);
FORCEPROP 1 LASTPIN (1950 3100) BN 1
J 0
(1938 3108);
DISPLAY 0.680851 (1938 3108);
PAINT GREEN (1938 3108);
FORCEPROP 2 LAST CDS_LIB standard
J 0
(2000 3100);
DISPLAY INVISIBLE (2000 3100);
FORCEPROP 1 LAST BODY_TYPE PLUMBING
J 0
(2000 3150);
DISPLAY 0.872340 (2000 3150);
PAINT GREEN (2000 3150);
DISPLAY INVISIBLE (2000 3150);
FORCEPROP 1 LAST HDL_TAP TRUE
J 0
(2325 2975);
DISPLAY 0.872340 (2325 2975);
DISPLAY INVISIBLE (2325 2975);
FORCEPROP 1 LAST PATH I151
J 0
(1998 3100);
DISPLAY 0.872340 (1998 3100);
PAINT GREEN (1998 3100);
DISPLAY INVISIBLE (1998 3100);
FORCEADD TAP..1
(2000 3000);
FORCEPROP 3 LASTPIN (1950 3000) SIG_NAME M_G_CPU1_SA_DQS_DN<0>
J 0
(1960 3010);
DISPLAY 0.659574 (1960 3010);
PAINT MONO (1960 3010);
DISPLAY INVISIBLE (1960 3010);
FORCEPROP 1 LASTPIN (1950 3000) BN 0
J 0
(1938 3008);
DISPLAY 0.680851 (1938 3008);
PAINT GREEN (1938 3008);
FORCEPROP 2 LAST CDS_LIB standard
J 0
(2000 3000);
PAINT MONO (2000 3000);
DISPLAY INVISIBLE (2000 3000);
FORCEPROP 1 LAST BODY_TYPE PLUMBING
J 0
(2000 3050);
DISPLAY 0.872340 (2000 3050);
PAINT GREEN (2000 3050);
DISPLAY INVISIBLE (2000 3050);
FORCEPROP 1 LAST HDL_TAP TRUE
J 0
(2325 2875);
DISPLAY 0.872340 (2325 2875);
DISPLAY INVISIBLE (2325 2875);
FORCEPROP 1 LAST PATH I152
J 0
(1998 3000);
DISPLAY 0.872340 (1998 3000);
PAINT GREEN (1998 3000);
DISPLAY INVISIBLE (1998 3000);
FORCEADD TAP..1
(1825 3250);
FORCEPROP 3 LASTPIN (1775 3250) SIG_NAME M_G_CPU1_SA_DQS_DP<2>
J 0
(1785 3260);
DISPLAY 0.659574 (1785 3260);
PAINT MONO (1785 3260);
DISPLAY INVISIBLE (1785 3260);
FORCEPROP 1 LASTPIN (1775 3250) BN 2
J 0
(1763 3258);
DISPLAY 0.680851 (1763 3258);
PAINT GREEN (1763 3258);
FORCEPROP 2 LAST CDS_LIB standard
J 0
(1825 3250);
DISPLAY INVISIBLE (1825 3250);
FORCEPROP 1 LAST BODY_TYPE PLUMBING
J 0
(1825 3300);
DISPLAY 0.872340 (1825 3300);
PAINT GREEN (1825 3300);
DISPLAY INVISIBLE (1825 3300);
FORCEPROP 1 LAST HDL_TAP TRUE
J 0
(2150 3125);
DISPLAY 0.872340 (2150 3125);
DISPLAY INVISIBLE (2150 3125);
FORCEPROP 1 LAST PATH I153
J 0
(1823 3250);
DISPLAY 0.872340 (1823 3250);
PAINT GREEN (1823 3250);
DISPLAY INVISIBLE (1823 3250);
FORCEADD TAP..1
(1825 3350);
FORCEPROP 3 LASTPIN (1775 3350) SIG_NAME M_G_CPU1_SA_DQS_DP<3>
J 0
(1785 3360);
DISPLAY 0.659574 (1785 3360);
PAINT MONO (1785 3360);
DISPLAY INVISIBLE (1785 3360);
FORCEPROP 1 LASTPIN (1775 3350) BN 3
J 0
(1763 3358);
DISPLAY 0.680851 (1763 3358);
PAINT GREEN (1763 3358);
FORCEPROP 2 LAST CDS_LIB standard
J 0
(1825 3350);
PAINT MONO (1825 3350);
DISPLAY INVISIBLE (1825 3350);
FORCEPROP 1 LAST BODY_TYPE PLUMBING
J 0
(1825 3400);
DISPLAY 0.872340 (1825 3400);
PAINT GREEN (1825 3400);
DISPLAY INVISIBLE (1825 3400);
FORCEPROP 1 LAST HDL_TAP TRUE
J 0
(2150 3225);
DISPLAY 0.872340 (2150 3225);
DISPLAY INVISIBLE (2150 3225);
FORCEPROP 1 LAST PATH I154
J 0
(1823 3350);
DISPLAY 0.872340 (1823 3350);
PAINT GREEN (1823 3350);
DISPLAY INVISIBLE (1823 3350);
FORCEADD TAP..1
(2000 3200);
FORCEPROP 3 LASTPIN (1950 3200) SIG_NAME M_G_CPU1_SA_DQS_DN<2>
J 0
(1960 3210);
DISPLAY 0.659574 (1960 3210);
PAINT MONO (1960 3210);
DISPLAY INVISIBLE (1960 3210);
FORCEPROP 1 LASTPIN (1950 3200) BN 2
J 0
(1938 3208);
DISPLAY 0.680851 (1938 3208);
PAINT GREEN (1938 3208);
FORCEPROP 2 LAST CDS_LIB standard
J 0
(2000 3200);
DISPLAY INVISIBLE (2000 3200);
FORCEPROP 1 LAST BODY_TYPE PLUMBING
J 0
(2000 3250);
DISPLAY 0.872340 (2000 3250);
PAINT GREEN (2000 3250);
DISPLAY INVISIBLE (2000 3250);
FORCEPROP 1 LAST HDL_TAP TRUE
J 0
(2325 3075);
DISPLAY 0.872340 (2325 3075);
DISPLAY INVISIBLE (2325 3075);
FORCEPROP 1 LAST PATH I155
J 0
(1998 3200);
DISPLAY 0.872340 (1998 3200);
PAINT GREEN (1998 3200);
DISPLAY INVISIBLE (1998 3200);
FORCEADD TAP..1
(2000 3300);
FORCEPROP 3 LASTPIN (1950 3300) SIG_NAME M_G_CPU1_SA_DQS_DN<3>
J 0
(1960 3310);
DISPLAY 0.659574 (1960 3310);
PAINT MONO (1960 3310);
DISPLAY INVISIBLE (1960 3310);
FORCEPROP 1 LASTPIN (1950 3300) BN 3
J 0
(1938 3308);
DISPLAY 0.680851 (1938 3308);
PAINT GREEN (1938 3308);
FORCEPROP 2 LAST CDS_LIB standard
J 0
(2000 3300);
PAINT MONO (2000 3300);
DISPLAY INVISIBLE (2000 3300);
FORCEPROP 1 LAST BODY_TYPE PLUMBING
J 0
(2000 3350);
DISPLAY 0.872340 (2000 3350);
PAINT GREEN (2000 3350);
DISPLAY INVISIBLE (2000 3350);
FORCEPROP 1 LAST HDL_TAP TRUE
J 0
(2325 3175);
DISPLAY 0.872340 (2325 3175);
DISPLAY INVISIBLE (2325 3175);
FORCEPROP 1 LAST PATH I156
J 0
(1998 3300);
DISPLAY 0.872340 (1998 3300);
PAINT GREEN (1998 3300);
DISPLAY INVISIBLE (1998 3300);
FORCEADD TAP..1
(2000 3400);
FORCEPROP 3 LASTPIN (1950 3400) SIG_NAME M_G_CPU1_SA_DQS_DN<4>
J 0
(1960 3410);
DISPLAY 0.659574 (1960 3410);
PAINT MONO (1960 3410);
DISPLAY INVISIBLE (1960 3410);
FORCEPROP 1 LASTPIN (1950 3400) BN 4
J 0
(1938 3408);
DISPLAY 0.680851 (1938 3408);
PAINT GREEN (1938 3408);
FORCEPROP 2 LAST CDS_LIB standard
J 0
(2000 3400);
PAINT MONO (2000 3400);
DISPLAY INVISIBLE (2000 3400);
FORCEPROP 1 LAST BODY_TYPE PLUMBING
J 0
(2000 3450);
DISPLAY 0.872340 (2000 3450);
PAINT GREEN (2000 3450);
DISPLAY INVISIBLE (2000 3450);
FORCEPROP 1 LAST HDL_TAP TRUE
J 0
(2325 3275);
DISPLAY 0.872340 (2325 3275);
DISPLAY INVISIBLE (2325 3275);
FORCEPROP 1 LAST PATH I157
J 0
(1998 3400);
DISPLAY 0.872340 (1998 3400);
PAINT GREEN (1998 3400);
DISPLAY INVISIBLE (1998 3400);
FORCEADD TAP..1
(1825 3450);
FORCEPROP 3 LASTPIN (1775 3450) SIG_NAME M_G_CPU1_SA_DQS_DP<4>
J 0
(1785 3460);
DISPLAY 0.659574 (1785 3460);
PAINT MONO (1785 3460);
DISPLAY INVISIBLE (1785 3460);
FORCEPROP 1 LASTPIN (1775 3450) BN 4
J 0
(1763 3458);
DISPLAY 0.680851 (1763 3458);
PAINT GREEN (1763 3458);
FORCEPROP 2 LAST CDS_LIB standard
J 0
(1825 3450);
PAINT MONO (1825 3450);
DISPLAY INVISIBLE (1825 3450);
FORCEPROP 1 LAST BODY_TYPE PLUMBING
J 0
(1825 3500);
DISPLAY 0.872340 (1825 3500);
PAINT GREEN (1825 3500);
DISPLAY INVISIBLE (1825 3500);
FORCEPROP 1 LAST HDL_TAP TRUE
J 0
(2150 3325);
DISPLAY 0.872340 (2150 3325);
DISPLAY INVISIBLE (2150 3325);
FORCEPROP 1 LAST PATH I158
J 0
(1823 3450);
DISPLAY 0.872340 (1823 3450);
PAINT GREEN (1823 3450);
DISPLAY INVISIBLE (1823 3450);
FORCEADD TAP..1
(1825 3550);
FORCEPROP 3 LASTPIN (1775 3550) SIG_NAME M_G_CPU1_SA_DQS_DP<5>
J 0
(1785 3560);
DISPLAY 0.659574 (1785 3560);
PAINT MONO (1785 3560);
DISPLAY INVISIBLE (1785 3560);
FORCEPROP 1 LASTPIN (1775 3550) BN 5
J 0
(1763 3558);
DISPLAY 0.680851 (1763 3558);
PAINT GREEN (1763 3558);
FORCEPROP 2 LAST CDS_LIB standard
J 0
(1825 3550);
DISPLAY INVISIBLE (1825 3550);
FORCEPROP 1 LAST BODY_TYPE PLUMBING
J 0
(1825 3600);
DISPLAY 0.872340 (1825 3600);
PAINT GREEN (1825 3600);
DISPLAY INVISIBLE (1825 3600);
FORCEPROP 1 LAST HDL_TAP TRUE
J 0
(2150 3425);
DISPLAY 0.872340 (2150 3425);
DISPLAY INVISIBLE (2150 3425);
FORCEPROP 1 LAST PATH I159
J 0
(1823 3550);
DISPLAY 0.872340 (1823 3550);
PAINT GREEN (1823 3550);
DISPLAY INVISIBLE (1823 3550);
FORCEADD OFFPAGE..1
(-3500 2800);
FORCEPROP 2 LAST $XR0 57 
J 0
(-3721 2800);
DISPLAY 0.638298 (-3721 2800);
PAINT MONO (-3721 2800);
FORCEPROP 2 LAST CDS_LIB standard
J 0
(-3500 2800);
PAINT MONO (-3500 2800);
DISPLAY INVISIBLE (-3500 2800);
FORCEPROP 1 LAST OFFPAGE TRUE
J 0
(-3175 2675);
DISPLAY 0.872340 (-3175 2675);
DISPLAY INVISIBLE (-3175 2675);
FORCEPROP 1 LAST COMMENT_BODY TRUE
J 0
(-3375 2700);
DISPLAY 0.872340 (-3375 2700);
PAINT GREEN (-3375 2700);
DISPLAY INVISIBLE (-3375 2700);
FORCEPROP 2 LAST PATH I16
J 0
(-3450 2875);
DISPLAY 1.021277 (-3450 2875);
DISPLAY INVISIBLE (-3450 2875);
FORCEADD TAP..1
(1825 3650);
FORCEPROP 3 LASTPIN (1775 3650) SIG_NAME M_G_CPU1_SA_DQS_DP<6>
J 0
(1785 3660);
DISPLAY 0.659574 (1785 3660);
PAINT MONO (1785 3660);
DISPLAY INVISIBLE (1785 3660);
FORCEPROP 1 LASTPIN (1775 3650) BN 6
J 0
(1763 3658);
DISPLAY 0.680851 (1763 3658);
PAINT GREEN (1763 3658);
FORCEPROP 2 LAST CDS_LIB standard
J 0
(1825 3650);
DISPLAY INVISIBLE (1825 3650);
FORCEPROP 1 LAST BODY_TYPE PLUMBING
J 0
(1825 3700);
DISPLAY 0.872340 (1825 3700);
PAINT GREEN (1825 3700);
DISPLAY INVISIBLE (1825 3700);
FORCEPROP 1 LAST HDL_TAP TRUE
J 0
(2150 3525);
DISPLAY 0.872340 (2150 3525);
DISPLAY INVISIBLE (2150 3525);
FORCEPROP 1 LAST PATH I160
J 0
(1823 3650);
DISPLAY 0.872340 (1823 3650);
PAINT GREEN (1823 3650);
DISPLAY INVISIBLE (1823 3650);
FORCEADD TAP..1
(2000 3600);
FORCEPROP 3 LASTPIN (1950 3600) SIG_NAME M_G_CPU1_SA_DQS_DN<6>
J 0
(1960 3610);
DISPLAY 0.659574 (1960 3610);
PAINT MONO (1960 3610);
DISPLAY INVISIBLE (1960 3610);
FORCEPROP 1 LASTPIN (1950 3600) BN 6
J 0
(1938 3608);
DISPLAY 0.680851 (1938 3608);
PAINT GREEN (1938 3608);
FORCEPROP 2 LAST CDS_LIB standard
J 0
(2000 3600);
DISPLAY INVISIBLE (2000 3600);
FORCEPROP 1 LAST BODY_TYPE PLUMBING
J 0
(2000 3650);
DISPLAY 0.872340 (2000 3650);
PAINT GREEN (2000 3650);
DISPLAY INVISIBLE (2000 3650);
FORCEPROP 1 LAST HDL_TAP TRUE
J 0
(2325 3475);
DISPLAY 0.872340 (2325 3475);
DISPLAY INVISIBLE (2325 3475);
FORCEPROP 1 LAST PATH I161
J 0
(1998 3600);
DISPLAY 0.872340 (1998 3600);
PAINT GREEN (1998 3600);
DISPLAY INVISIBLE (1998 3600);
FORCEADD TAP..1
(2000 3500);
FORCEPROP 3 LASTPIN (1950 3500) SIG_NAME M_G_CPU1_SA_DQS_DN<5>
J 0
(1960 3510);
DISPLAY 0.659574 (1960 3510);
PAINT MONO (1960 3510);
DISPLAY INVISIBLE (1960 3510);
FORCEPROP 1 LASTPIN (1950 3500) BN 5
J 0
(1938 3508);
DISPLAY 0.680851 (1938 3508);
PAINT GREEN (1938 3508);
FORCEPROP 2 LAST CDS_LIB standard
J 0
(2000 3500);
DISPLAY INVISIBLE (2000 3500);
FORCEPROP 1 LAST BODY_TYPE PLUMBING
J 0
(2000 3550);
DISPLAY 0.872340 (2000 3550);
PAINT GREEN (2000 3550);
DISPLAY INVISIBLE (2000 3550);
FORCEPROP 1 LAST HDL_TAP TRUE
J 0
(2325 3375);
DISPLAY 0.872340 (2325 3375);
DISPLAY INVISIBLE (2325 3375);
FORCEPROP 1 LAST PATH I162
J 0
(1998 3500);
DISPLAY 0.872340 (1998 3500);
PAINT GREEN (1998 3500);
DISPLAY INVISIBLE (1998 3500);
FORCEADD OFFPAGE..2
(2950 2875);
FORCEPROP 2 LAST $XR1 111 
J 0
(3229 2875);
DISPLAY 0.638298 (3229 2875);
PAINT MONO (3229 2875);
FORCEPROP 2 LAST $XR0 57 
J 0
(3139 2875);
DISPLAY 0.638298 (3139 2875);
PAINT MONO (3139 2875);
FORCEPROP 2 LAST CDS_LIB standard
J 0
(2950 2875);
PAINT MONO (2950 2875);
DISPLAY INVISIBLE (2950 2875);
FORCEPROP 1 LAST OFFPAGE TRUE
J 0
(3275 2750);
DISPLAY 1.170213 (3275 2750);
PAINT GREEN (3275 2750);
DISPLAY INVISIBLE (3275 2750);
FORCEPROP 1 LAST COMMENT_BODY TRUE
J 0
(2905 2780);
DISPLAY 1.170213 (2905 2780);
PAINT GREEN (2905 2780);
DISPLAY INVISIBLE (2905 2780);
FORCEPROP 2 LAST PATH I163
J 0
(3125 2950);
DISPLAY 1.021277 (3125 2950);
DISPLAY INVISIBLE (3125 2950);
FORCEADD OFFPAGE..2
(2950 2925);
FORCEPROP 2 LAST $XR1 111 
J 0
(3229 2925);
DISPLAY 0.638298 (3229 2925);
PAINT MONO (3229 2925);
FORCEPROP 2 LAST $XR0 57 
J 0
(3139 2925);
DISPLAY 0.638298 (3139 2925);
PAINT MONO (3139 2925);
FORCEPROP 2 LAST CDS_LIB standard
J 0
(2950 2925);
PAINT MONO (2950 2925);
DISPLAY INVISIBLE (2950 2925);
FORCEPROP 1 LAST OFFPAGE TRUE
J 0
(3275 2800);
DISPLAY 1.170213 (3275 2800);
PAINT GREEN (3275 2800);
DISPLAY INVISIBLE (3275 2800);
FORCEPROP 1 LAST COMMENT_BODY TRUE
J 0
(2905 2830);
DISPLAY 1.170213 (2905 2830);
PAINT GREEN (2905 2830);
DISPLAY INVISIBLE (2905 2830);
FORCEPROP 2 LAST PATH I164
J 0
(3125 3000);
DISPLAY 1.021277 (3125 3000);
DISPLAY INVISIBLE (3125 3000);
FORCEADD OFFPAGE..3
(-100 3975);
FORCEPROP 2 LAST $XR1 111 
J 0
(204 3975);
DISPLAY 0.638298 (204 3975);
PAINT MONO (204 3975);
FORCEPROP 2 LAST $XR0 57 
J 0
(114 3975);
DISPLAY 0.638298 (114 3975);
PAINT MONO (114 3975);
FORCEPROP 2 LAST CDS_LIB standard
J 2
(-100 3975);
DISPLAY INVISIBLE (-100 3975);
FORCEPROP 1 LAST OFFPAGE TRUE
J 0
(225 3850);
DISPLAY 0.872340 (225 3850);
DISPLAY INVISIBLE (225 3850);
FORCEPROP 1 LAST COMMENT_BODY TRUE
J 0
(-150 3875);
DISPLAY 0.872340 (-150 3875);
PAINT GREEN (-150 3875);
DISPLAY INVISIBLE (-150 3875);
FORCEPROP 2 LAST PATH I165
J 0
(100 4050);
DISPLAY 1.021277 (100 4050);
DISPLAY INVISIBLE (100 4050);
FORCEADD TAP..1
(1825 3750);
FORCEPROP 3 LASTPIN (1775 3750) SIG_NAME M_G_CPU1_SA_DQS_DP<7>
J 0
(1785 3760);
DISPLAY 0.659574 (1785 3760);
PAINT MONO (1785 3760);
DISPLAY INVISIBLE (1785 3760);
FORCEPROP 1 LASTPIN (1775 3750) BN 7
J 0
(1763 3758);
DISPLAY 0.680851 (1763 3758);
PAINT GREEN (1763 3758);
FORCEPROP 2 LAST CDS_LIB standard
J 0
(1825 3750);
DISPLAY INVISIBLE (1825 3750);
FORCEPROP 1 LAST BODY_TYPE PLUMBING
J 0
(1825 3800);
DISPLAY 0.872340 (1825 3800);
PAINT GREEN (1825 3800);
DISPLAY INVISIBLE (1825 3800);
FORCEPROP 1 LAST HDL_TAP TRUE
J 0
(2150 3625);
DISPLAY 0.872340 (2150 3625);
DISPLAY INVISIBLE (2150 3625);
FORCEPROP 1 LAST PATH I166
J 0
(1823 3750);
DISPLAY 0.872340 (1823 3750);
PAINT GREEN (1823 3750);
DISPLAY INVISIBLE (1823 3750);
FORCEADD TAP..1
(1825 3850);
FORCEPROP 3 LASTPIN (1775 3850) SIG_NAME M_G_CPU1_SA_DQS_DP<8>
J 0
(1785 3860);
DISPLAY 0.659574 (1785 3860);
PAINT MONO (1785 3860);
DISPLAY INVISIBLE (1785 3860);
FORCEPROP 1 LASTPIN (1775 3850) BN 8
J 0
(1763 3858);
DISPLAY 0.680851 (1763 3858);
PAINT GREEN (1763 3858);
FORCEPROP 2 LAST CDS_LIB standard
J 0
(1825 3850);
DISPLAY INVISIBLE (1825 3850);
FORCEPROP 1 LAST BODY_TYPE PLUMBING
J 0
(1825 3900);
DISPLAY 0.872340 (1825 3900);
PAINT GREEN (1825 3900);
DISPLAY INVISIBLE (1825 3900);
FORCEPROP 1 LAST HDL_TAP TRUE
J 0
(2150 3725);
DISPLAY 0.872340 (2150 3725);
DISPLAY INVISIBLE (2150 3725);
FORCEPROP 1 LAST PATH I167
J 0
(1823 3850);
DISPLAY 0.872340 (1823 3850);
PAINT GREEN (1823 3850);
DISPLAY INVISIBLE (1823 3850);
FORCEADD TAP..1
(1825 3950);
FORCEPROP 3 LASTPIN (1775 3950) SIG_NAME M_G_CPU1_SA_DQS_DP<9>
J 0
(1785 3960);
DISPLAY 0.659574 (1785 3960);
PAINT MONO (1785 3960);
DISPLAY INVISIBLE (1785 3960);
FORCEPROP 1 LASTPIN (1775 3950) BN 9
J 0
(1763 3958);
DISPLAY 0.680851 (1763 3958);
PAINT GREEN (1763 3958);
FORCEPROP 2 LAST CDS_LIB standard
J 0
(1825 3950);
DISPLAY INVISIBLE (1825 3950);
FORCEPROP 1 LAST BODY_TYPE PLUMBING
J 0
(1825 4000);
DISPLAY 0.872340 (1825 4000);
PAINT GREEN (1825 4000);
DISPLAY INVISIBLE (1825 4000);
FORCEPROP 1 LAST HDL_TAP TRUE
J 0
(2150 3825);
DISPLAY 0.872340 (2150 3825);
DISPLAY INVISIBLE (2150 3825);
FORCEPROP 1 LAST PATH I168
J 0
(1823 3950);
DISPLAY 0.872340 (1823 3950);
PAINT GREEN (1823 3950);
DISPLAY INVISIBLE (1823 3950);
FORCEADD TAP..1
(2000 3900);
FORCEPROP 3 LASTPIN (1950 3900) SIG_NAME M_G_CPU1_SA_DQS_DN<9>
J 0
(1960 3910);
DISPLAY 0.659574 (1960 3910);
PAINT MONO (1960 3910);
DISPLAY INVISIBLE (1960 3910);
FORCEPROP 1 LASTPIN (1950 3900) BN 9
J 0
(1938 3908);
DISPLAY 0.680851 (1938 3908);
PAINT GREEN (1938 3908);
FORCEPROP 2 LAST CDS_LIB standard
J 0
(2000 3900);
DISPLAY INVISIBLE (2000 3900);
FORCEPROP 1 LAST BODY_TYPE PLUMBING
J 0
(2000 3950);
DISPLAY 0.872340 (2000 3950);
PAINT GREEN (2000 3950);
DISPLAY INVISIBLE (2000 3950);
FORCEPROP 1 LAST HDL_TAP TRUE
J 0
(2325 3775);
DISPLAY 0.872340 (2325 3775);
DISPLAY INVISIBLE (2325 3775);
FORCEPROP 1 LAST PATH I169
J 0
(1998 3900);
DISPLAY 0.872340 (1998 3900);
PAINT GREEN (1998 3900);
DISPLAY INVISIBLE (1998 3900);
FORCEADD OFFPAGE..1
(-3500 2950);
FORCEPROP 2 LAST $XR0 57 
J 0
(-3721 2950);
DISPLAY 0.638298 (-3721 2950);
PAINT MONO (-3721 2950);
FORCEPROP 2 LAST CDS_LIB standard
J 0
(-3500 2950);
PAINT MONO (-3500 2950);
DISPLAY INVISIBLE (-3500 2950);
FORCEPROP 1 LAST OFFPAGE TRUE
J 0
(-3175 2825);
DISPLAY 0.872340 (-3175 2825);
DISPLAY INVISIBLE (-3175 2825);
FORCEPROP 1 LAST COMMENT_BODY TRUE
J 0
(-3375 2850);
DISPLAY 0.872340 (-3375 2850);
PAINT GREEN (-3375 2850);
DISPLAY INVISIBLE (-3375 2850);
FORCEPROP 2 LAST PATH I17
J 0
(-3450 3025);
DISPLAY 1.021277 (-3450 3025);
DISPLAY INVISIBLE (-3450 3025);
FORCEADD TAP..1
(2000 3800);
FORCEPROP 3 LASTPIN (1950 3800) SIG_NAME M_G_CPU1_SA_DQS_DN<8>
J 0
(1960 3810);
DISPLAY 0.659574 (1960 3810);
PAINT MONO (1960 3810);
DISPLAY INVISIBLE (1960 3810);
FORCEPROP 1 LASTPIN (1950 3800) BN 8
J 0
(1938 3808);
DISPLAY 0.680851 (1938 3808);
PAINT GREEN (1938 3808);
FORCEPROP 2 LAST CDS_LIB standard
J 0
(2000 3800);
DISPLAY INVISIBLE (2000 3800);
FORCEPROP 1 LAST BODY_TYPE PLUMBING
J 0
(2000 3850);
DISPLAY 0.872340 (2000 3850);
PAINT GREEN (2000 3850);
DISPLAY INVISIBLE (2000 3850);
FORCEPROP 1 LAST HDL_TAP TRUE
J 0
(2325 3675);
DISPLAY 0.872340 (2325 3675);
DISPLAY INVISIBLE (2325 3675);
FORCEPROP 1 LAST PATH I170
J 0
(1998 3800);
DISPLAY 0.872340 (1998 3800);
PAINT GREEN (1998 3800);
DISPLAY INVISIBLE (1998 3800);
FORCEADD TAP..1
(2000 3700);
FORCEPROP 3 LASTPIN (1950 3700) SIG_NAME M_G_CPU1_SA_DQS_DN<7>
J 0
(1960 3710);
DISPLAY 0.659574 (1960 3710);
PAINT MONO (1960 3710);
DISPLAY INVISIBLE (1960 3710);
FORCEPROP 1 LASTPIN (1950 3700) BN 7
J 0
(1938 3708);
DISPLAY 0.680851 (1938 3708);
PAINT GREEN (1938 3708);
FORCEPROP 2 LAST CDS_LIB standard
J 0
(2000 3700);
DISPLAY INVISIBLE (2000 3700);
FORCEPROP 1 LAST BODY_TYPE PLUMBING
J 0
(2000 3750);
DISPLAY 0.872340 (2000 3750);
PAINT GREEN (2000 3750);
DISPLAY INVISIBLE (2000 3750);
FORCEPROP 1 LAST HDL_TAP TRUE
J 0
(2325 3575);
DISPLAY 0.872340 (2325 3575);
DISPLAY INVISIBLE (2325 3575);
FORCEPROP 1 LAST PATH I171
J 0
(1998 3700);
DISPLAY 0.872340 (1998 3700);
PAINT GREEN (1998 3700);
DISPLAY INVISIBLE (1998 3700);
FORCEADD OFFPAGE..2
(2950 3925);
FORCEPROP 2 LAST $XR1 111 
J 0
(3229 3925);
DISPLAY 0.638298 (3229 3925);
PAINT MONO (3229 3925);
FORCEPROP 2 LAST $XR0 57 
J 0
(3139 3925);
DISPLAY 0.638298 (3139 3925);
PAINT MONO (3139 3925);
FORCEPROP 2 LAST CDS_LIB standard
J 0
(2950 3925);
PAINT MONO (2950 3925);
DISPLAY INVISIBLE (2950 3925);
FORCEPROP 1 LAST OFFPAGE TRUE
J 0
(3275 3800);
DISPLAY 1.170213 (3275 3800);
PAINT GREEN (3275 3800);
DISPLAY INVISIBLE (3275 3800);
FORCEPROP 1 LAST COMMENT_BODY TRUE
J 0
(2905 3830);
DISPLAY 1.170213 (2905 3830);
PAINT GREEN (2905 3830);
DISPLAY INVISIBLE (2905 3830);
FORCEPROP 2 LAST PATH I172
J 0
(3125 4000);
DISPLAY 1.021277 (3125 4000);
DISPLAY INVISIBLE (3125 4000);
FORCEADD OFFPAGE..2
(2950 3975);
FORCEPROP 2 LAST $XR1 111 
J 0
(3229 3975);
DISPLAY 0.638298 (3229 3975);
PAINT MONO (3229 3975);
FORCEPROP 2 LAST $XR0 57 
J 0
(3139 3975);
DISPLAY 0.638298 (3139 3975);
PAINT MONO (3139 3975);
FORCEPROP 2 LAST CDS_LIB standard
J 0
(2950 3975);
PAINT MONO (2950 3975);
DISPLAY INVISIBLE (2950 3975);
FORCEPROP 1 LAST OFFPAGE TRUE
J 0
(3275 3850);
DISPLAY 1.170213 (3275 3850);
PAINT GREEN (3275 3850);
DISPLAY INVISIBLE (3275 3850);
FORCEPROP 1 LAST COMMENT_BODY TRUE
J 0
(2905 3880);
DISPLAY 1.170213 (2905 3880);
PAINT GREEN (2905 3880);
DISPLAY INVISIBLE (2905 3880);
FORCEPROP 2 LAST PATH I173
J 0
(3125 4050);
DISPLAY 1.021277 (3125 4050);
DISPLAY INVISIBLE (3125 4050);
FORCEADD VCC_CORE..1
(3500 4500);
FORCEPROP 3 LASTPIN (3500 4450) SIG_NAME P12V_S3_AUX_CPU1_NVDIMM\g
J 0
(3510 4460);
DISPLAY 0.659574 (3510 4460);
PAINT MONO (3510 4460);
DISPLAY INVISIBLE (3510 4460);
FORCEPROP 1 LAST HDL_POWER P12V_S3_AUX_CPU1_NVDIMM
J 1
(3500 4550);
DISPLAY 1.148936 (3500 4550);
PAINT GREEN (3500 4550);
FORCEPROP 2 LAST CDS_LIB logical_power
J 0
(3500 4500);
PAINT MONO (3500 4500);
DISPLAY INVISIBLE (3500 4500);
FORCEPROP 1 LAST PATH I174
J 0
(3550 4525);
DISPLAY 0.872340 (3550 4525);
PAINT AQUA (3550 4525);
DISPLAY INVISIBLE (3550 4525);
FORCEADD UNIVERSAL_GND..1
(5200 250);
FORCEPROP 3 LASTPIN (5200 300) SIG_NAME GND\g
J 0
(5210 310);
DISPLAY 0.659574 (5210 310);
PAINT MONO (5210 310);
DISPLAY INVISIBLE (5210 310);
FORCEPROP 1 LAST PATH I176
J 0
(5275 250);
DISPLAY 0.872340 (5275 250);
PAINT AQUA (5275 250);
DISPLAY INVISIBLE (5275 250);
FORCEPROP 1 LAST HDL_POWER GND
J 1
(5225 175);
DISPLAY 0.872340 (5225 175);
PAINT GREEN (5225 175);
DISPLAY INVISIBLE (5225 175);
FORCEPROP 2 LAST CDS_LIB logical_power
J 0
(5200 250);
PAINT MONO (5200 250);
DISPLAY INVISIBLE (5200 250);
FORCEADD SCONN288_ADR50017P130CC..3
(4350 2325);
FORCEPROP 1 LAST PART_NUMBER DFHST8FS461
J 0
(3895 4249);
DISPLAY 0.723404 (3895 4249);
PAINT GREEN (3895 4249);
DISPLAY INVISIBLE (3895 4249);
FORCEPROP 1 LAST MATERIAL IO
J 0
(3895 4122);
DISPLAY 0.723404 (3895 4122);
PAINT GREEN (3895 4122);
FORCEPROP 2 LAST PART_TYPE SMLF
J 0
(3900 4400);
DISPLAY 1.021277 (3900 4400);
FORCEPROP 2 LAST VALUE SCONN288_ADR50017-P130CC
J 0
(3900 4350);
DISPLAY 1.021277 (3900 4350);
FORCEPROP 1 LAST $LOCATION J29
J 0
(3900 4300);
DISPLAY 0.723404 (3900 4300);
PAINT GREEN (3900 4300);
FORCEPROP 0 LASTPIN (4950 700) $PN G1
J 0
(4960 710);
DISPLAY 0.680851 (4960 710);
PAINT MONO (4960 710);
FORCEPROP 0 LASTPIN (4950 650) $PN G2
J 0
(4960 660);
DISPLAY 0.680851 (4960 660);
PAINT MONO (4960 660);
FORCEPROP 0 LASTPIN (4950 600) $PN G3
J 0
(4960 610);
DISPLAY 0.680851 (4960 610);
PAINT MONO (4960 610);
FORCEPROP 0 LASTPIN (3750 3850) $PN 1
J 2
(3740 3860);
DISPLAY 0.680851 (3740 3860);
PAINT MONO (3740 3860);
FORCEPROP 0 LASTPIN (3750 3900) $PN 145
J 2
(3740 3910);
DISPLAY 0.680851 (3740 3910);
PAINT MONO (3740 3910);
FORCEPROP 0 LASTPIN (3750 3950) $PN 146
J 2
(3740 3960);
DISPLAY 0.680851 (3740 3960);
PAINT MONO (3740 3960);
FORCEPROP 0 LASTPIN (4950 800) $PN 6
J 0
(4960 810);
DISPLAY 0.680851 (4960 810);
PAINT MONO (4960 810);
FORCEPROP 0 LASTPIN (4950 850) $PN 8
J 0
(4960 860);
DISPLAY 0.680851 (4960 860);
PAINT MONO (4960 860);
FORCEPROP 0 LASTPIN (4950 900) $PN 10
J 0
(4960 910);
DISPLAY 0.680851 (4960 910);
PAINT MONO (4960 910);
FORCEPROP 0 LASTPIN (4950 950) $PN 13
J 0
(4960 960);
DISPLAY 0.680851 (4960 960);
PAINT MONO (4960 960);
FORCEPROP 0 LASTPIN (4950 1000) $PN 15
J 0
(4960 1010);
DISPLAY 0.680851 (4960 1010);
PAINT MONO (4960 1010);
FORCEPROP 0 LASTPIN (4950 1050) $PN 17
J 0
(4960 1060);
DISPLAY 0.680851 (4960 1060);
PAINT MONO (4960 1060);
FORCEPROP 0 LASTPIN (4950 1100) $PN 19
J 0
(4960 1110);
DISPLAY 0.680851 (4960 1110);
PAINT MONO (4960 1110);
FORCEPROP 0 LASTPIN (4950 1150) $PN 21
J 0
(4960 1160);
DISPLAY 0.680851 (4960 1160);
PAINT MONO (4960 1160);
FORCEPROP 0 LASTPIN (4950 1200) $PN 24
J 0
(4960 1210);
DISPLAY 0.680851 (4960 1210);
PAINT MONO (4960 1210);
FORCEPROP 0 LASTPIN (4950 1250) $PN 26
J 0
(4960 1260);
DISPLAY 0.680851 (4960 1260);
PAINT MONO (4960 1260);
FORCEPROP 0 LASTPIN (4950 1300) $PN 28
J 0
(4960 1310);
DISPLAY 0.680851 (4960 1310);
PAINT MONO (4960 1310);
FORCEPROP 0 LASTPIN (4950 1350) $PN 30
J 0
(4960 1360);
DISPLAY 0.680851 (4960 1360);
PAINT MONO (4960 1360);
FORCEPROP 0 LASTPIN (4950 1400) $PN 32
J 0
(4960 1410);
DISPLAY 0.680851 (4960 1410);
PAINT MONO (4960 1410);
FORCEPROP 0 LASTPIN (4950 1450) $PN 35
J 0
(4960 1460);
DISPLAY 0.680851 (4960 1460);
PAINT MONO (4960 1460);
FORCEPROP 0 LASTPIN (4950 1500) $PN 37
J 0
(4960 1510);
DISPLAY 0.680851 (4960 1510);
PAINT MONO (4960 1510);
FORCEPROP 0 LASTPIN (4950 1550) $PN 39
J 0
(4960 1560);
DISPLAY 0.680851 (4960 1560);
PAINT MONO (4960 1560);
FORCEPROP 0 LASTPIN (4950 1600) $PN 41
J 0
(4960 1610);
DISPLAY 0.680851 (4960 1610);
PAINT MONO (4960 1610);
FORCEPROP 0 LASTPIN (4950 1650) $PN 43
J 0
(4960 1660);
DISPLAY 0.680851 (4960 1660);
PAINT MONO (4960 1660);
FORCEPROP 0 LASTPIN (4950 1700) $PN 46
J 0
(4960 1710);
DISPLAY 0.680851 (4960 1710);
PAINT MONO (4960 1710);
FORCEPROP 0 LASTPIN (4950 1750) $PN 48
J 0
(4960 1760);
DISPLAY 0.680851 (4960 1760);
PAINT MONO (4960 1760);
FORCEPROP 0 LASTPIN (4950 1800) $PN 50
J 0
(4960 1810);
DISPLAY 0.680851 (4960 1810);
PAINT MONO (4960 1810);
FORCEPROP 0 LASTPIN (4950 1850) $PN 52
J 0
(4960 1860);
DISPLAY 0.680851 (4960 1860);
PAINT MONO (4960 1860);
FORCEPROP 0 LASTPIN (4950 1900) $PN 54
J 0
(4960 1910);
DISPLAY 0.680851 (4960 1910);
PAINT MONO (4960 1910);
FORCEPROP 0 LASTPIN (4950 1950) $PN 57
J 0
(4960 1960);
DISPLAY 0.680851 (4960 1960);
PAINT MONO (4960 1960);
FORCEPROP 0 LASTPIN (4950 2000) $PN 59
J 0
(4960 2010);
DISPLAY 0.680851 (4960 2010);
PAINT MONO (4960 2010);
FORCEPROP 0 LASTPIN (4950 2050) $PN 61
J 0
(4960 2060);
DISPLAY 0.680851 (4960 2060);
PAINT MONO (4960 2060);
FORCEPROP 0 LASTPIN (4950 2100) $PN 63
J 0
(4960 2110);
DISPLAY 0.680851 (4960 2110);
PAINT MONO (4960 2110);
FORCEPROP 0 LASTPIN (4950 2150) $PN 65
J 0
(4960 2160);
DISPLAY 0.680851 (4960 2160);
PAINT MONO (4960 2160);
FORCEPROP 0 LASTPIN (4950 2200) $PN 67
J 0
(4960 2210);
DISPLAY 0.680851 (4960 2210);
PAINT MONO (4960 2210);
FORCEPROP 0 LASTPIN (4950 2250) $PN 69
J 0
(4960 2260);
DISPLAY 0.680851 (4960 2260);
PAINT MONO (4960 2260);
FORCEPROP 0 LASTPIN (4950 2300) $PN 71
J 0
(4960 2310);
DISPLAY 0.680851 (4960 2310);
PAINT MONO (4960 2310);
FORCEPROP 0 LASTPIN (4950 2350) $PN 73
J 0
(4960 2360);
DISPLAY 0.680851 (4960 2360);
PAINT MONO (4960 2360);
FORCEPROP 0 LASTPIN (4950 2400) $PN 75
J 0
(4960 2410);
DISPLAY 0.680851 (4960 2410);
PAINT MONO (4960 2410);
FORCEPROP 0 LASTPIN (4950 2450) $PN 77
J 0
(4960 2460);
DISPLAY 0.680851 (4960 2460);
PAINT MONO (4960 2460);
FORCEPROP 0 LASTPIN (4950 2500) $PN 79
J 0
(4960 2510);
DISPLAY 0.680851 (4960 2510);
PAINT MONO (4960 2510);
FORCEPROP 0 LASTPIN (4950 2550) $PN 81
J 0
(4960 2560);
DISPLAY 0.680851 (4960 2560);
PAINT MONO (4960 2560);
FORCEPROP 0 LASTPIN (4950 2600) $PN 83
J 0
(4960 2610);
DISPLAY 0.680851 (4960 2610);
PAINT MONO (4960 2610);
FORCEPROP 0 LASTPIN (4950 2650) $PN 85
J 0
(4960 2660);
DISPLAY 0.680851 (4960 2660);
PAINT MONO (4960 2660);
FORCEPROP 0 LASTPIN (4950 2700) $PN 88
J 0
(4960 2710);
DISPLAY 0.680851 (4960 2710);
PAINT MONO (4960 2710);
FORCEPROP 0 LASTPIN (4950 2750) $PN 90
J 0
(4960 2760);
DISPLAY 0.680851 (4960 2760);
PAINT MONO (4960 2760);
FORCEPROP 0 LASTPIN (4950 2800) $PN 92
J 0
(4960 2810);
DISPLAY 0.680851 (4960 2810);
PAINT MONO (4960 2810);
FORCEPROP 0 LASTPIN (4950 2850) $PN 95
J 0
(4960 2860);
DISPLAY 0.680851 (4960 2860);
PAINT MONO (4960 2860);
FORCEPROP 0 LASTPIN (4950 2900) $PN 97
J 0
(4960 2910);
DISPLAY 0.680851 (4960 2910);
PAINT MONO (4960 2910);
FORCEPROP 0 LASTPIN (4950 2950) $PN 99
J 0
(4960 2960);
DISPLAY 0.680851 (4960 2960);
PAINT MONO (4960 2960);
FORCEPROP 0 LASTPIN (4950 3000) $PN 101
J 0
(4960 3010);
DISPLAY 0.680851 (4960 3010);
PAINT MONO (4960 3010);
FORCEPROP 0 LASTPIN (4950 3050) $PN 103
J 0
(4960 3060);
DISPLAY 0.680851 (4960 3060);
PAINT MONO (4960 3060);
FORCEPROP 0 LASTPIN (4950 3100) $PN 106
J 0
(4960 3110);
DISPLAY 0.680851 (4960 3110);
PAINT MONO (4960 3110);
FORCEPROP 0 LASTPIN (4950 3150) $PN 108
J 0
(4960 3160);
DISPLAY 0.680851 (4960 3160);
PAINT MONO (4960 3160);
FORCEPROP 0 LASTPIN (4950 3200) $PN 110
J 0
(4960 3210);
DISPLAY 0.680851 (4960 3210);
PAINT MONO (4960 3210);
FORCEPROP 0 LASTPIN (4950 3250) $PN 112
J 0
(4960 3260);
DISPLAY 0.680851 (4960 3260);
PAINT MONO (4960 3260);
FORCEPROP 0 LASTPIN (4950 3300) $PN 114
J 0
(4960 3310);
DISPLAY 0.680851 (4960 3310);
PAINT MONO (4960 3310);
FORCEPROP 0 LASTPIN (4950 3350) $PN 117
J 0
(4960 3360);
DISPLAY 0.680851 (4960 3360);
PAINT MONO (4960 3360);
FORCEPROP 0 LASTPIN (4950 3400) $PN 119
J 0
(4960 3410);
DISPLAY 0.680851 (4960 3410);
PAINT MONO (4960 3410);
FORCEPROP 0 LASTPIN (4950 3450) $PN 121
J 0
(4960 3460);
DISPLAY 0.680851 (4960 3460);
PAINT MONO (4960 3460);
FORCEPROP 0 LASTPIN (4950 3500) $PN 123
J 0
(4960 3510);
DISPLAY 0.680851 (4960 3510);
PAINT MONO (4960 3510);
FORCEPROP 0 LASTPIN (4950 3550) $PN 125
J 0
(4960 3560);
DISPLAY 0.680851 (4960 3560);
PAINT MONO (4960 3560);
FORCEPROP 0 LASTPIN (4950 3600) $PN 128
J 0
(4960 3610);
DISPLAY 0.680851 (4960 3610);
PAINT MONO (4960 3610);
FORCEPROP 0 LASTPIN (4950 3650) $PN 130
J 0
(4960 3660);
DISPLAY 0.680851 (4960 3660);
PAINT MONO (4960 3660);
FORCEPROP 0 LASTPIN (4950 3700) $PN 132
J 0
(4960 3710);
DISPLAY 0.680851 (4960 3710);
PAINT MONO (4960 3710);
FORCEPROP 0 LASTPIN (4950 3750) $PN 134
J 0
(4960 3760);
DISPLAY 0.680851 (4960 3760);
PAINT MONO (4960 3760);
FORCEPROP 0 LASTPIN (4950 3800) $PN 136
J 0
(4960 3810);
DISPLAY 0.680851 (4960 3810);
PAINT MONO (4960 3810);
FORCEPROP 0 LASTPIN (4950 3850) $PN 139
J 0
(4960 3860);
DISPLAY 0.680851 (4960 3860);
PAINT MONO (4960 3860);
FORCEPROP 0 LASTPIN (4950 3900) $PN 141
J 0
(4960 3910);
DISPLAY 0.680851 (4960 3910);
PAINT MONO (4960 3910);
FORCEPROP 0 LASTPIN (4950 3950) $PN 143
J 0
(4960 3960);
DISPLAY 0.680851 (4960 3960);
PAINT MONO (4960 3960);
FORCEPROP 0 LASTPIN (3750 700) $PN 151
J 2
(3740 710);
DISPLAY 0.680851 (3740 710);
PAINT MONO (3740 710);
FORCEPROP 0 LASTPIN (3750 750) $PN 153
J 2
(3740 760);
DISPLAY 0.680851 (3740 760);
PAINT MONO (3740 760);
FORCEPROP 0 LASTPIN (3750 800) $PN 155
J 2
(3740 810);
DISPLAY 0.680851 (3740 810);
PAINT MONO (3740 810);
FORCEPROP 0 LASTPIN (3750 850) $PN 158
J 2
(3740 860);
DISPLAY 0.680851 (3740 860);
PAINT MONO (3740 860);
FORCEPROP 0 LASTPIN (3750 900) $PN 160
J 2
(3740 910);
DISPLAY 0.680851 (3740 910);
PAINT MONO (3740 910);
FORCEPROP 0 LASTPIN (3750 950) $PN 162
J 2
(3740 960);
DISPLAY 0.680851 (3740 960);
PAINT MONO (3740 960);
FORCEPROP 0 LASTPIN (3750 1000) $PN 164
J 2
(3740 1010);
DISPLAY 0.680851 (3740 1010);
PAINT MONO (3740 1010);
FORCEPROP 0 LASTPIN (3750 1050) $PN 166
J 2
(3740 1060);
DISPLAY 0.680851 (3740 1060);
PAINT MONO (3740 1060);
FORCEPROP 0 LASTPIN (3750 1100) $PN 169
J 2
(3740 1110);
DISPLAY 0.680851 (3740 1110);
PAINT MONO (3740 1110);
FORCEPROP 0 LASTPIN (3750 1150) $PN 171
J 2
(3740 1160);
DISPLAY 0.680851 (3740 1160);
PAINT MONO (3740 1160);
FORCEPROP 0 LASTPIN (3750 1200) $PN 173
J 2
(3740 1210);
DISPLAY 0.680851 (3740 1210);
PAINT MONO (3740 1210);
FORCEPROP 0 LASTPIN (3750 1250) $PN 175
J 2
(3740 1260);
DISPLAY 0.680851 (3740 1260);
PAINT MONO (3740 1260);
FORCEPROP 0 LASTPIN (3750 1300) $PN 177
J 2
(3740 1310);
DISPLAY 0.680851 (3740 1310);
PAINT MONO (3740 1310);
FORCEPROP 0 LASTPIN (3750 1350) $PN 180
J 2
(3740 1360);
DISPLAY 0.680851 (3740 1360);
PAINT MONO (3740 1360);
FORCEPROP 0 LASTPIN (3750 1400) $PN 182
J 2
(3740 1410);
DISPLAY 0.680851 (3740 1410);
PAINT MONO (3740 1410);
FORCEPROP 0 LASTPIN (3750 1450) $PN 184
J 2
(3740 1460);
DISPLAY 0.680851 (3740 1460);
PAINT MONO (3740 1460);
FORCEPROP 0 LASTPIN (3750 1500) $PN 186
J 2
(3740 1510);
DISPLAY 0.680851 (3740 1510);
PAINT MONO (3740 1510);
FORCEPROP 0 LASTPIN (3750 1550) $PN 188
J 2
(3740 1560);
DISPLAY 0.680851 (3740 1560);
PAINT MONO (3740 1560);
FORCEPROP 0 LASTPIN (3750 1600) $PN 191
J 2
(3740 1610);
DISPLAY 0.680851 (3740 1610);
PAINT MONO (3740 1610);
FORCEPROP 0 LASTPIN (3750 1650) $PN 193
J 2
(3740 1660);
DISPLAY 0.680851 (3740 1660);
PAINT MONO (3740 1660);
FORCEPROP 0 LASTPIN (3750 1700) $PN 195
J 2
(3740 1710);
DISPLAY 0.680851 (3740 1710);
PAINT MONO (3740 1710);
FORCEPROP 0 LASTPIN (3750 1750) $PN 197
J 2
(3740 1760);
DISPLAY 0.680851 (3740 1760);
PAINT MONO (3740 1760);
FORCEPROP 0 LASTPIN (3750 1800) $PN 199
J 2
(3740 1810);
DISPLAY 0.680851 (3740 1810);
PAINT MONO (3740 1810);
FORCEPROP 0 LASTPIN (3750 1850) $PN 202
J 2
(3740 1860);
DISPLAY 0.680851 (3740 1860);
PAINT MONO (3740 1860);
FORCEPROP 0 LASTPIN (3750 1900) $PN 204
J 2
(3740 1910);
DISPLAY 0.680851 (3740 1910);
PAINT MONO (3740 1910);
FORCEPROP 0 LASTPIN (3750 1950) $PN 206
J 2
(3740 1960);
DISPLAY 0.680851 (3740 1960);
PAINT MONO (3740 1960);
FORCEPROP 0 LASTPIN (3750 2000) $PN 208
J 2
(3740 2010);
DISPLAY 0.680851 (3740 2010);
PAINT MONO (3740 2010);
FORCEPROP 0 LASTPIN (3750 2050) $PN 210
J 2
(3740 2060);
DISPLAY 0.680851 (3740 2060);
PAINT MONO (3740 2060);
FORCEPROP 0 LASTPIN (3750 2100) $PN 212
J 2
(3740 2110);
DISPLAY 0.680851 (3740 2110);
PAINT MONO (3740 2110);
FORCEPROP 0 LASTPIN (3750 2150) $PN 214
J 2
(3740 2160);
DISPLAY 0.680851 (3740 2160);
PAINT MONO (3740 2160);
FORCEPROP 0 LASTPIN (3750 2200) $PN 216
J 2
(3740 2210);
DISPLAY 0.680851 (3740 2210);
PAINT MONO (3740 2210);
FORCEPROP 0 LASTPIN (3750 2250) $PN 219
J 2
(3740 2260);
DISPLAY 0.680851 (3740 2260);
PAINT MONO (3740 2260);
FORCEPROP 0 LASTPIN (3750 2300) $PN 222
J 2
(3740 2310);
DISPLAY 0.680851 (3740 2310);
PAINT MONO (3740 2310);
FORCEPROP 0 LASTPIN (3750 2350) $PN 224
J 2
(3740 2360);
DISPLAY 0.680851 (3740 2360);
PAINT MONO (3740 2360);
FORCEPROP 0 LASTPIN (3750 2400) $PN 226
J 2
(3740 2410);
DISPLAY 0.680851 (3740 2410);
PAINT MONO (3740 2410);
FORCEPROP 0 LASTPIN (3750 2450) $PN 228
J 2
(3740 2460);
DISPLAY 0.680851 (3740 2460);
PAINT MONO (3740 2460);
FORCEPROP 0 LASTPIN (3750 2500) $PN 230
J 2
(3740 2510);
DISPLAY 0.680851 (3740 2510);
PAINT MONO (3740 2510);
FORCEPROP 0 LASTPIN (3750 2550) $PN 233
J 2
(3740 2560);
DISPLAY 0.680851 (3740 2560);
PAINT MONO (3740 2560);
FORCEPROP 0 LASTPIN (3750 2600) $PN 235
J 2
(3740 2610);
DISPLAY 0.680851 (3740 2610);
PAINT MONO (3740 2610);
FORCEPROP 0 LASTPIN (3750 2650) $PN 237
J 2
(3740 2660);
DISPLAY 0.680851 (3740 2660);
PAINT MONO (3740 2660);
FORCEPROP 0 LASTPIN (3750 2700) $PN 240
J 2
(3740 2710);
DISPLAY 0.680851 (3740 2710);
PAINT MONO (3740 2710);
FORCEPROP 0 LASTPIN (3750 2750) $PN 242
J 2
(3740 2760);
DISPLAY 0.680851 (3740 2760);
PAINT MONO (3740 2760);
FORCEPROP 0 LASTPIN (3750 2800) $PN 244
J 2
(3740 2810);
DISPLAY 0.680851 (3740 2810);
PAINT MONO (3740 2810);
FORCEPROP 0 LASTPIN (3750 2850) $PN 246
J 2
(3740 2860);
DISPLAY 0.680851 (3740 2860);
PAINT MONO (3740 2860);
FORCEPROP 0 LASTPIN (3750 2900) $PN 248
J 2
(3740 2910);
DISPLAY 0.680851 (3740 2910);
PAINT MONO (3740 2910);
FORCEPROP 0 LASTPIN (3750 2950) $PN 251
J 2
(3740 2960);
DISPLAY 0.680851 (3740 2960);
PAINT MONO (3740 2960);
FORCEPROP 0 LASTPIN (3750 3000) $PN 253
J 2
(3740 3010);
DISPLAY 0.680851 (3740 3010);
PAINT MONO (3740 3010);
FORCEPROP 0 LASTPIN (3750 3050) $PN 255
J 2
(3740 3060);
DISPLAY 0.680851 (3740 3060);
PAINT MONO (3740 3060);
FORCEPROP 0 LASTPIN (3750 3100) $PN 257
J 2
(3740 3110);
DISPLAY 0.680851 (3740 3110);
PAINT MONO (3740 3110);
FORCEPROP 0 LASTPIN (3750 3150) $PN 259
J 2
(3740 3160);
DISPLAY 0.680851 (3740 3160);
PAINT MONO (3740 3160);
FORCEPROP 0 LASTPIN (3750 3200) $PN 262
J 2
(3740 3210);
DISPLAY 0.680851 (3740 3210);
PAINT MONO (3740 3210);
FORCEPROP 0 LASTPIN (3750 3250) $PN 264
J 2
(3740 3260);
DISPLAY 0.680851 (3740 3260);
PAINT MONO (3740 3260);
FORCEPROP 0 LASTPIN (3750 3300) $PN 266
J 2
(3740 3310);
DISPLAY 0.680851 (3740 3310);
PAINT MONO (3740 3310);
FORCEPROP 0 LASTPIN (3750 3350) $PN 268
J 2
(3740 3360);
DISPLAY 0.680851 (3740 3360);
PAINT MONO (3740 3360);
FORCEPROP 0 LASTPIN (3750 3400) $PN 270
J 2
(3740 3410);
DISPLAY 0.680851 (3740 3410);
PAINT MONO (3740 3410);
FORCEPROP 0 LASTPIN (3750 3450) $PN 273
J 2
(3740 3460);
DISPLAY 0.680851 (3740 3460);
PAINT MONO (3740 3460);
FORCEPROP 0 LASTPIN (3750 3500) $PN 275
J 2
(3740 3510);
DISPLAY 0.680851 (3740 3510);
PAINT MONO (3740 3510);
FORCEPROP 0 LASTPIN (3750 3550) $PN 277
J 2
(3740 3560);
DISPLAY 0.680851 (3740 3560);
PAINT MONO (3740 3560);
FORCEPROP 0 LASTPIN (3750 3600) $PN 279
J 2
(3740 3610);
DISPLAY 0.680851 (3740 3610);
PAINT MONO (3740 3610);
FORCEPROP 0 LASTPIN (3750 3650) $PN 281
J 2
(3740 3660);
DISPLAY 0.680851 (3740 3660);
PAINT MONO (3740 3660);
FORCEPROP 0 LASTPIN (3750 3700) $PN 284
J 2
(3740 3710);
DISPLAY 0.680851 (3740 3710);
PAINT MONO (3740 3710);
FORCEPROP 0 LASTPIN (3750 3750) $PN 286
J 2
(3740 3760);
DISPLAY 0.680851 (3740 3760);
PAINT MONO (3740 3760);
FORCEPROP 0 LASTPIN (3750 3800) $PN 288
J 2
(3740 3810);
DISPLAY 0.680851 (3740 3810);
PAINT MONO (3740 3810);
FORCEPROP 1 LAST NEEDS_NO_SIZE TRUE
J 0
(4350 2325);
DISPLAY 0.723404 (4350 2325);
PAINT GREEN (4350 2325);
DISPLAY INVISIBLE (4350 2325);
FORCEPROP 1 LAST CDS_LMAN_SYM_OUTLINE -450,1775,450,-1775
J 0
(4350 2325);
DISPLAY 0.468085 (4350 2325);
PAINT GREEN (4350 2325);
DISPLAY INVISIBLE (4350 2325);
FORCEPROP 2 LAST CDS_LIB pure_quanta
J 0
(4350 2325);
DISPLAY INVISIBLE (4350 2325);
FORCEPROP 1 LAST PATH I178
J 0
(4350 2325);
DISPLAY 0.723404 (4350 2325);
PAINT GREEN (4350 2325);
DISPLAY INVISIBLE (4350 2325);
FORCEPROP 2 LAST CDS_LOCATION J29
J 0
(3900 4450);
DISPLAY 1.021277 (3900 4450);
DISPLAY INVISIBLE (3900 4450);
FORCEPROP 0 LAST $SEC 3
J 0
(3900 4450);
DISPLAY 0.680851 (3900 4450);
PAINT MONO (3900 4450);
DISPLAY INVISIBLE (3900 4450);
FORCEPROP 2 LAST CDS_SEC 3
J 0
(3900 4450);
DISPLAY 1.021277 (3900 4450);
DISPLAY INVISIBLE (3900 4450);
FORCEADD SCONN288_ADR50017P130CC..1
(-1750 2225);
FORCEPROP 1 LAST PART_NUMBER DFHST8FS461
J 0
(-2195 4247);
DISPLAY 0.723404 (-2195 4247);
PAINT GREEN (-2195 4247);
DISPLAY INVISIBLE (-2195 4247);
FORCEPROP 1 LAST MATERIAL IO
J 0
(-2195 4120);
DISPLAY 0.723404 (-2195 4120);
PAINT GREEN (-2195 4120);
FORCEPROP 2 LAST VALUE SCONN288_ADR50017-P130CC
J 0
(-2200 4350);
DISPLAY 1.021277 (-2200 4350);
FORCEPROP 2 LAST PART_TYPE SMLF
J 0
(-2200 4400);
DISPLAY 1.021277 (-2200 4400);
FORCEPROP 1 LAST $LOCATION J29
J 0
(-2200 4300);
DISPLAY 0.723404 (-2200 4300);
PAINT GREEN (-2200 4300);
FORCEPROP 0 LASTPIN (-2350 1600) $PN 62
J 2
(-2360 1610);
DISPLAY 0.680851 (-2360 1610);
PAINT MONO (-2360 1610);
FORCEPROP 0 LASTPIN (-2350 3650) $PN 66
J 2
(-2360 3660);
DISPLAY 0.680851 (-2360 3660);
PAINT MONO (-2360 3660);
FORCEPROP 0 LASTPIN (-2350 3250) $PN 76
J 2
(-2360 3260);
DISPLAY 0.680851 (-2360 3260);
PAINT MONO (-2360 3260);
FORCEPROP 0 LASTPIN (-2350 3700) $PN 211
J 2
(-2360 3710);
DISPLAY 0.680851 (-2360 3710);
PAINT MONO (-2360 3710);
FORCEPROP 0 LASTPIN (-2350 3300) $PN 221
J 2
(-2360 3310);
DISPLAY 0.680851 (-2360 3310);
PAINT MONO (-2360 3310);
FORCEPROP 0 LASTPIN (-2350 3750) $PN 68
J 2
(-2360 3760);
DISPLAY 0.680851 (-2360 3760);
PAINT MONO (-2360 3760);
FORCEPROP 0 LASTPIN (-2350 3350) $PN 78
J 2
(-2360 3360);
DISPLAY 0.680851 (-2360 3360);
PAINT MONO (-2360 3360);
FORCEPROP 0 LASTPIN (-2350 3800) $PN 213
J 2
(-2360 3810);
DISPLAY 0.680851 (-2360 3810);
PAINT MONO (-2360 3810);
FORCEPROP 0 LASTPIN (-2350 3400) $PN 223
J 2
(-2360 3410);
DISPLAY 0.680851 (-2360 3410);
PAINT MONO (-2360 3410);
FORCEPROP 0 LASTPIN (-2350 3850) $PN 70
J 2
(-2360 3860);
DISPLAY 0.680851 (-2360 3860);
PAINT MONO (-2360 3860);
FORCEPROP 0 LASTPIN (-2350 3450) $PN 80
J 2
(-2360 3460);
DISPLAY 0.680851 (-2360 3460);
PAINT MONO (-2360 3460);
FORCEPROP 0 LASTPIN (-2350 3900) $PN 215
J 2
(-2360 3910);
DISPLAY 0.680851 (-2360 3910);
PAINT MONO (-2360 3910);
FORCEPROP 0 LASTPIN (-2350 3500) $PN 225
J 2
(-2360 3510);
DISPLAY 0.680851 (-2360 3510);
PAINT MONO (-2360 3510);
FORCEPROP 0 LASTPIN (-2350 3950) $PN 72
J 2
(-2360 3960);
DISPLAY 0.680851 (-2360 3960);
PAINT MONO (-2360 3960);
FORCEPROP 0 LASTPIN (-2350 3550) $PN 82
J 2
(-2360 3560);
DISPLAY 0.680851 (-2360 3560);
PAINT MONO (-2360 3560);
FORCEPROP 0 LASTPIN (-2350 2200) $PN 51
J 2
(-2360 2210);
DISPLAY 0.680851 (-2360 2210);
PAINT MONO (-2360 2210);
FORCEPROP 0 LASTPIN (-2350 1750) $PN 96
J 2
(-2360 1760);
DISPLAY 0.680851 (-2360 1760);
PAINT MONO (-2360 1760);
FORCEPROP 0 LASTPIN (-2350 2250) $PN 53
J 2
(-2360 2260);
DISPLAY 0.680851 (-2360 2260);
PAINT MONO (-2360 2260);
FORCEPROP 0 LASTPIN (-2350 1800) $PN 98
J 2
(-2360 1810);
DISPLAY 0.680851 (-2360 1810);
PAINT MONO (-2360 1810);
FORCEPROP 0 LASTPIN (-2350 2300) $PN 196
J 2
(-2360 2310);
DISPLAY 0.680851 (-2360 2310);
PAINT MONO (-2360 2310);
FORCEPROP 0 LASTPIN (-2350 1850) $PN 241
J 2
(-2360 1860);
DISPLAY 0.680851 (-2360 1860);
PAINT MONO (-2360 1860);
FORCEPROP 0 LASTPIN (-2350 2350) $PN 198
J 2
(-2360 2360);
DISPLAY 0.680851 (-2360 2360);
PAINT MONO (-2360 2360);
FORCEPROP 0 LASTPIN (-2350 1900) $PN 243
J 2
(-2360 1910);
DISPLAY 0.680851 (-2360 1910);
PAINT MONO (-2360 1910);
FORCEPROP 0 LASTPIN (-2350 2400) $PN 58
J 2
(-2360 2410);
DISPLAY 0.680851 (-2360 2410);
PAINT MONO (-2360 2410);
FORCEPROP 0 LASTPIN (-2350 1950) $PN 89
J 2
(-2360 1960);
DISPLAY 0.680851 (-2360 1960);
PAINT MONO (-2360 1960);
FORCEPROP 0 LASTPIN (-2350 2450) $PN 60
J 2
(-2360 2460);
DISPLAY 0.680851 (-2360 2460);
PAINT MONO (-2360 2460);
FORCEPROP 0 LASTPIN (-2350 2000) $PN 91
J 2
(-2360 2010);
DISPLAY 0.680851 (-2360 2010);
PAINT MONO (-2360 2010);
FORCEPROP 0 LASTPIN (-2350 2500) $PN 203
J 2
(-2360 2510);
DISPLAY 0.680851 (-2360 2510);
PAINT MONO (-2360 2510);
FORCEPROP 0 LASTPIN (-2350 2050) $PN 234
J 2
(-2360 2060);
DISPLAY 0.680851 (-2360 2060);
PAINT MONO (-2360 2060);
FORCEPROP 0 LASTPIN (-2350 2550) $PN 205
J 2
(-2360 2560);
DISPLAY 0.680851 (-2360 2560);
PAINT MONO (-2360 2560);
FORCEPROP 0 LASTPIN (-2350 2100) $PN 236
J 2
(-2360 2110);
DISPLAY 0.680851 (-2360 2110);
PAINT MONO (-2360 2110);
FORCEPROP 0 LASTPIN (-2350 2650) $PN 218
J 2
(-2360 2660);
DISPLAY 0.680851 (-2360 2660);
PAINT MONO (-2360 2660);
FORCEPROP 0 LASTPIN (-2350 2700) $PN 217
J 2
(-2360 2710);
DISPLAY 0.680851 (-2360 2710);
PAINT MONO (-2360 2710);
FORCEPROP 0 LASTPIN (-2350 2950) $PN 64
J 2
(-2360 2960);
DISPLAY 0.680851 (-2360 2960);
PAINT MONO (-2360 2960);
FORCEPROP 0 LASTPIN (-2350 2800) $PN 84
J 2
(-2360 2810);
DISPLAY 0.680851 (-2360 2810);
PAINT MONO (-2360 2810);
FORCEPROP 0 LASTPIN (-2350 3000) $PN 209
J 2
(-2360 3010);
DISPLAY 0.680851 (-2360 3010);
PAINT MONO (-2360 3010);
FORCEPROP 0 LASTPIN (-2350 2850) $PN 229
J 2
(-2360 2860);
DISPLAY 0.680851 (-2360 2860);
PAINT MONO (-2360 2860);
FORCEPROP 0 LASTPIN (-1150 2400) $PN 7
J 0
(-1140 2410);
DISPLAY 0.680851 (-1140 2410);
PAINT MONO (-1140 2410);
FORCEPROP 0 LASTPIN (-1150 750) $PN 100
J 0
(-1140 760);
DISPLAY 0.680851 (-1140 760);
PAINT MONO (-1140 760);
FORCEPROP 0 LASTPIN (-1150 2450) $PN 9
J 0
(-1140 2460);
DISPLAY 0.680851 (-1140 2460);
PAINT MONO (-1140 2460);
FORCEPROP 0 LASTPIN (-1150 800) $PN 102
J 0
(-1140 810);
DISPLAY 0.680851 (-1140 810);
PAINT MONO (-1140 810);
FORCEPROP 0 LASTPIN (-1150 2500) $PN 152
J 0
(-1140 2510);
DISPLAY 0.680851 (-1140 2510);
PAINT MONO (-1140 2510);
FORCEPROP 0 LASTPIN (-1150 850) $PN 245
J 0
(-1140 860);
DISPLAY 0.680851 (-1140 860);
PAINT MONO (-1140 860);
FORCEPROP 0 LASTPIN (-1150 2550) $PN 154
J 0
(-1140 2560);
DISPLAY 0.680851 (-1140 2560);
PAINT MONO (-1140 2560);
FORCEPROP 0 LASTPIN (-1150 900) $PN 247
J 0
(-1140 910);
DISPLAY 0.680851 (-1140 910);
PAINT MONO (-1140 910);
FORCEPROP 0 LASTPIN (-1150 2600) $PN 14
J 0
(-1140 2610);
DISPLAY 0.680851 (-1140 2610);
PAINT MONO (-1140 2610);
FORCEPROP 0 LASTPIN (-1150 950) $PN 107
J 0
(-1140 960);
DISPLAY 0.680851 (-1140 960);
PAINT MONO (-1140 960);
FORCEPROP 0 LASTPIN (-1150 2650) $PN 16
J 0
(-1140 2660);
DISPLAY 0.680851 (-1140 2660);
PAINT MONO (-1140 2660);
FORCEPROP 0 LASTPIN (-1150 1000) $PN 109
J 0
(-1140 1010);
DISPLAY 0.680851 (-1140 1010);
PAINT MONO (-1140 1010);
FORCEPROP 0 LASTPIN (-1150 2700) $PN 159
J 0
(-1140 2710);
DISPLAY 0.680851 (-1140 2710);
PAINT MONO (-1140 2710);
FORCEPROP 0 LASTPIN (-1150 1050) $PN 252
J 0
(-1140 1060);
DISPLAY 0.680851 (-1140 1060);
PAINT MONO (-1140 1060);
FORCEPROP 0 LASTPIN (-1150 2750) $PN 161
J 0
(-1140 2760);
DISPLAY 0.680851 (-1140 2760);
PAINT MONO (-1140 2760);
FORCEPROP 0 LASTPIN (-1150 1100) $PN 254
J 0
(-1140 1110);
DISPLAY 0.680851 (-1140 1110);
PAINT MONO (-1140 1110);
FORCEPROP 0 LASTPIN (-1150 2800) $PN 18
J 0
(-1140 2810);
DISPLAY 0.680851 (-1140 2810);
PAINT MONO (-1140 2810);
FORCEPROP 0 LASTPIN (-1150 1150) $PN 111
J 0
(-1140 1160);
DISPLAY 0.680851 (-1140 1160);
PAINT MONO (-1140 1160);
FORCEPROP 0 LASTPIN (-1150 2850) $PN 20
J 0
(-1140 2860);
DISPLAY 0.680851 (-1140 2860);
PAINT MONO (-1140 2860);
FORCEPROP 0 LASTPIN (-1150 1200) $PN 113
J 0
(-1140 1210);
DISPLAY 0.680851 (-1140 1210);
PAINT MONO (-1140 1210);
FORCEPROP 0 LASTPIN (-1150 2900) $PN 163
J 0
(-1140 2910);
DISPLAY 0.680851 (-1140 2910);
PAINT MONO (-1140 2910);
FORCEPROP 0 LASTPIN (-1150 1250) $PN 256
J 0
(-1140 1260);
DISPLAY 0.680851 (-1140 1260);
PAINT MONO (-1140 1260);
FORCEPROP 0 LASTPIN (-1150 2950) $PN 165
J 0
(-1140 2960);
DISPLAY 0.680851 (-1140 2960);
PAINT MONO (-1140 2960);
FORCEPROP 0 LASTPIN (-1150 1300) $PN 258
J 0
(-1140 1310);
DISPLAY 0.680851 (-1140 1310);
PAINT MONO (-1140 1310);
FORCEPROP 0 LASTPIN (-1150 3000) $PN 25
J 0
(-1140 3010);
DISPLAY 0.680851 (-1140 3010);
PAINT MONO (-1140 3010);
FORCEPROP 0 LASTPIN (-1150 1350) $PN 118
J 0
(-1140 1360);
DISPLAY 0.680851 (-1140 1360);
PAINT MONO (-1140 1360);
FORCEPROP 0 LASTPIN (-1150 3050) $PN 27
J 0
(-1140 3060);
DISPLAY 0.680851 (-1140 3060);
PAINT MONO (-1140 3060);
FORCEPROP 0 LASTPIN (-1150 1400) $PN 120
J 0
(-1140 1410);
DISPLAY 0.680851 (-1140 1410);
PAINT MONO (-1140 1410);
FORCEPROP 0 LASTPIN (-1150 3100) $PN 170
J 0
(-1140 3110);
DISPLAY 0.680851 (-1140 3110);
PAINT MONO (-1140 3110);
FORCEPROP 0 LASTPIN (-1150 1450) $PN 263
J 0
(-1140 1460);
DISPLAY 0.680851 (-1140 1460);
PAINT MONO (-1140 1460);
FORCEPROP 0 LASTPIN (-1150 3150) $PN 172
J 0
(-1140 3160);
DISPLAY 0.680851 (-1140 3160);
PAINT MONO (-1140 3160);
FORCEPROP 0 LASTPIN (-1150 1500) $PN 265
J 0
(-1140 1510);
DISPLAY 0.680851 (-1140 1510);
PAINT MONO (-1140 1510);
FORCEPROP 0 LASTPIN (-1150 3200) $PN 29
J 0
(-1140 3210);
DISPLAY 0.680851 (-1140 3210);
PAINT MONO (-1140 3210);
FORCEPROP 0 LASTPIN (-1150 1550) $PN 122
J 0
(-1140 1560);
DISPLAY 0.680851 (-1140 1560);
PAINT MONO (-1140 1560);
FORCEPROP 0 LASTPIN (-1150 3250) $PN 31
J 0
(-1140 3260);
DISPLAY 0.680851 (-1140 3260);
PAINT MONO (-1140 3260);
FORCEPROP 0 LASTPIN (-1150 1600) $PN 124
J 0
(-1140 1610);
DISPLAY 0.680851 (-1140 1610);
PAINT MONO (-1140 1610);
FORCEPROP 0 LASTPIN (-1150 3300) $PN 174
J 0
(-1140 3310);
DISPLAY 0.680851 (-1140 3310);
PAINT MONO (-1140 3310);
FORCEPROP 0 LASTPIN (-1150 1650) $PN 267
J 0
(-1140 1660);
DISPLAY 0.680851 (-1140 1660);
PAINT MONO (-1140 1660);
FORCEPROP 0 LASTPIN (-1150 3350) $PN 176
J 0
(-1140 3360);
DISPLAY 0.680851 (-1140 3360);
PAINT MONO (-1140 3360);
FORCEPROP 0 LASTPIN (-1150 1700) $PN 269
J 0
(-1140 1710);
DISPLAY 0.680851 (-1140 1710);
PAINT MONO (-1140 1710);
FORCEPROP 0 LASTPIN (-1150 3400) $PN 36
J 0
(-1140 3410);
DISPLAY 0.680851 (-1140 3410);
PAINT MONO (-1140 3410);
FORCEPROP 0 LASTPIN (-1150 1750) $PN 129
J 0
(-1140 1760);
DISPLAY 0.680851 (-1140 1760);
PAINT MONO (-1140 1760);
FORCEPROP 0 LASTPIN (-1150 3450) $PN 38
J 0
(-1140 3460);
DISPLAY 0.680851 (-1140 3460);
PAINT MONO (-1140 3460);
FORCEPROP 0 LASTPIN (-1150 1800) $PN 131
J 0
(-1140 1810);
DISPLAY 0.680851 (-1140 1810);
PAINT MONO (-1140 1810);
FORCEPROP 0 LASTPIN (-1150 3500) $PN 181
J 0
(-1140 3510);
DISPLAY 0.680851 (-1140 3510);
PAINT MONO (-1140 3510);
FORCEPROP 0 LASTPIN (-1150 1850) $PN 274
J 0
(-1140 1860);
DISPLAY 0.680851 (-1140 1860);
PAINT MONO (-1140 1860);
FORCEPROP 0 LASTPIN (-1150 3550) $PN 183
J 0
(-1140 3560);
DISPLAY 0.680851 (-1140 3560);
PAINT MONO (-1140 3560);
FORCEPROP 0 LASTPIN (-1150 1900) $PN 276
J 0
(-1140 1910);
DISPLAY 0.680851 (-1140 1910);
PAINT MONO (-1140 1910);
FORCEPROP 0 LASTPIN (-1150 3600) $PN 40
J 0
(-1140 3610);
DISPLAY 0.680851 (-1140 3610);
PAINT MONO (-1140 3610);
FORCEPROP 0 LASTPIN (-1150 1950) $PN 133
J 0
(-1140 1960);
DISPLAY 0.680851 (-1140 1960);
PAINT MONO (-1140 1960);
FORCEPROP 0 LASTPIN (-1150 3650) $PN 42
J 0
(-1140 3660);
DISPLAY 0.680851 (-1140 3660);
PAINT MONO (-1140 3660);
FORCEPROP 0 LASTPIN (-1150 2000) $PN 135
J 0
(-1140 2010);
DISPLAY 0.680851 (-1140 2010);
PAINT MONO (-1140 2010);
FORCEPROP 0 LASTPIN (-1150 3700) $PN 185
J 0
(-1140 3710);
DISPLAY 0.680851 (-1140 3710);
PAINT MONO (-1140 3710);
FORCEPROP 0 LASTPIN (-1150 2050) $PN 278
J 0
(-1140 2060);
DISPLAY 0.680851 (-1140 2060);
PAINT MONO (-1140 2060);
FORCEPROP 0 LASTPIN (-1150 3750) $PN 187
J 0
(-1140 3760);
DISPLAY 0.680851 (-1140 3760);
PAINT MONO (-1140 3760);
FORCEPROP 0 LASTPIN (-1150 2100) $PN 280
J 0
(-1140 2110);
DISPLAY 0.680851 (-1140 2110);
PAINT MONO (-1140 2110);
FORCEPROP 0 LASTPIN (-1150 3800) $PN 47
J 0
(-1140 3810);
DISPLAY 0.680851 (-1140 3810);
PAINT MONO (-1140 3810);
FORCEPROP 0 LASTPIN (-1150 2150) $PN 140
J 0
(-1140 2160);
DISPLAY 0.680851 (-1140 2160);
PAINT MONO (-1140 2160);
FORCEPROP 0 LASTPIN (-1150 3850) $PN 49
J 0
(-1140 3860);
DISPLAY 0.680851 (-1140 3860);
PAINT MONO (-1140 3860);
FORCEPROP 0 LASTPIN (-1150 2200) $PN 142
J 0
(-1140 2210);
DISPLAY 0.680851 (-1140 2210);
PAINT MONO (-1140 2210);
FORCEPROP 0 LASTPIN (-1150 3900) $PN 192
J 0
(-1140 3910);
DISPLAY 0.680851 (-1140 3910);
PAINT MONO (-1140 3910);
FORCEPROP 0 LASTPIN (-1150 2250) $PN 285
J 0
(-1140 2260);
DISPLAY 0.680851 (-1140 2260);
PAINT MONO (-1140 2260);
FORCEPROP 0 LASTPIN (-1150 3950) $PN 194
J 0
(-1140 3960);
DISPLAY 0.680851 (-1140 3960);
PAINT MONO (-1140 3960);
FORCEPROP 0 LASTPIN (-1150 2300) $PN 287
J 0
(-1140 2310);
DISPLAY 0.680851 (-1140 2310);
PAINT MONO (-1140 2310);
FORCEPROP 0 LASTPIN (-2350 1450) $PN 148
J 2
(-2360 1460);
DISPLAY 0.680851 (-2360 1460);
PAINT MONO (-2360 1460);
FORCEPROP 0 LASTPIN (-2350 1350) $PN 4
J 2
(-2360 1360);
DISPLAY 0.680851 (-2360 1360);
PAINT MONO (-2360 1360);
FORCEPROP 0 LASTPIN (-2350 1400) $PN 5
J 2
(-2360 1410);
DISPLAY 0.680851 (-2360 1410);
PAINT MONO (-2360 1410);
FORCEPROP 0 LASTPIN (-2350 550) $PN 86
J 2
(-2360 560);
DISPLAY 0.680851 (-2360 560);
PAINT MONO (-2360 560);
FORCEPROP 0 LASTPIN (-2350 500) $PN 87
J 2
(-2360 510);
DISPLAY 0.680851 (-2360 510);
PAINT MONO (-2360 510);
FORCEPROP 0 LASTPIN (-2350 3150) $PN 74
J 2
(-2360 3160);
DISPLAY 0.680851 (-2360 3160);
PAINT MONO (-2360 3160);
FORCEPROP 0 LASTPIN (-2350 3100) $PN 227
J 2
(-2360 3110);
DISPLAY 0.680851 (-2360 3110);
PAINT MONO (-2360 3110);
FORCEPROP 0 LASTPIN (-2350 1100) $PN 147
J 2
(-2360 1110);
DISPLAY 0.680851 (-2360 1110);
PAINT MONO (-2360 1110);
FORCEPROP 0 LASTPIN (-2350 1650) $PN 207
J 2
(-2360 1660);
DISPLAY 0.680851 (-2360 1660);
PAINT MONO (-2360 1660);
FORCEPROP 0 LASTPIN (-2350 700) $PN 2
J 2
(-2360 710);
DISPLAY 0.680851 (-2360 710);
PAINT MONO (-2360 710);
FORCEPROP 0 LASTPIN (-2350 750) $PN 144
J 2
(-2360 760);
DISPLAY 0.680851 (-2360 760);
PAINT MONO (-2360 760);
FORCEPROP 0 LASTPIN (-2350 800) $PN 149
J 2
(-2360 810);
DISPLAY 0.680851 (-2360 810);
PAINT MONO (-2360 810);
FORCEPROP 0 LASTPIN (-2350 850) $PN 150
J 2
(-2360 860);
DISPLAY 0.680851 (-2360 860);
PAINT MONO (-2360 860);
FORCEPROP 0 LASTPIN (-2350 900) $PN 220
J 2
(-2360 910);
DISPLAY 0.680851 (-2360 910);
PAINT MONO (-2360 910);
FORCEPROP 0 LASTPIN (-2350 950) $PN 231
J 2
(-2360 960);
DISPLAY 0.680851 (-2360 960);
PAINT MONO (-2360 960);
FORCEPROP 0 LASTPIN (-2350 1000) $PN 232
J 2
(-2360 1010);
DISPLAY 0.680851 (-2360 1010);
PAINT MONO (-2360 1010);
FORCEPROP 0 LASTPIN (-2350 1500) $PN 3
J 2
(-2360 1510);
DISPLAY 0.680851 (-2360 1510);
PAINT MONO (-2360 1510);
FORCEPROP 1 LAST NEEDS_NO_SIZE TRUE
J 0
(-1750 2225);
DISPLAY 0.723404 (-1750 2225);
PAINT GREEN (-1750 2225);
DISPLAY INVISIBLE (-1750 2225);
FORCEPROP 1 LAST CDS_LMAN_SYM_OUTLINE -450,1875,450,-1875
J 0
(-1750 2225);
DISPLAY 0.468085 (-1750 2225);
PAINT GREEN (-1750 2225);
DISPLAY INVISIBLE (-1750 2225);
FORCEPROP 2 LAST CDS_LIB pure_quanta
J 0
(-1750 2225);
DISPLAY INVISIBLE (-1750 2225);
FORCEPROP 1 LAST PATH I179
J 0
(-1750 2225);
DISPLAY 0.723404 (-1750 2225);
PAINT GREEN (-1750 2225);
DISPLAY INVISIBLE (-1750 2225);
FORCEPROP 2 LAST CDS_LOCATION J29
J 0
(-2200 4450);
DISPLAY 1.021277 (-2200 4450);
DISPLAY INVISIBLE (-2200 4450);
FORCEPROP 0 LAST $SEC 1
J 0
(-2175 4450);
DISPLAY 0.680851 (-2175 4450);
PAINT MONO (-2175 4450);
DISPLAY INVISIBLE (-2175 4450);
FORCEPROP 2 LAST CDS_SEC 1
J 0
(-2200 4450);
DISPLAY 1.021277 (-2200 4450);
DISPLAY INVISIBLE (-2200 4450);
FORCEADD OFFPAGE..1
(-3500 3150);
FORCEPROP 2 LAST $XR1 111 
J 0
(-3841 3150);
DISPLAY 0.638298 (-3841 3150);
PAINT MONO (-3841 3150);
FORCEPROP 2 LAST $XR0 57 
J 0
(-3721 3150);
DISPLAY 0.638298 (-3721 3150);
PAINT MONO (-3721 3150);
FORCEPROP 2 LAST CDS_LIB standard
J 0
(-3500 3150);
PAINT MONO (-3500 3150);
DISPLAY INVISIBLE (-3500 3150);
FORCEPROP 1 LAST OFFPAGE TRUE
J 0
(-3175 3025);
DISPLAY 0.872340 (-3175 3025);
DISPLAY INVISIBLE (-3175 3025);
FORCEPROP 1 LAST COMMENT_BODY TRUE
J 0
(-3375 3050);
DISPLAY 0.872340 (-3375 3050);
PAINT GREEN (-3375 3050);
DISPLAY INVISIBLE (-3375 3050);
FORCEPROP 2 LAST PATH I18
J 0
(-3450 3225);
DISPLAY 1.021277 (-3450 3225);
DISPLAY INVISIBLE (-3450 3225);
FORCEADD SCONN288_ADR50017P130CC..2
(925 2950);
FORCEPROP 1 LAST PART_NUMBER DFHST8FS461
J 0
(332 4250);
DISPLAY 0.723404 (332 4250);
PAINT GREEN (332 4250);
DISPLAY INVISIBLE (332 4250);
FORCEPROP 1 LAST MATERIAL IO
J 0
(332 4123);
DISPLAY 0.723404 (332 4123);
PAINT GREEN (332 4123);
FORCEPROP 2 LAST VALUE SCONN288_ADR50017-P130CC
J 0
(343 4353);
DISPLAY 1.021277 (343 4353);
FORCEPROP 2 LAST PART_TYPE SMLF
J 0
(343 4403);
DISPLAY 1.021277 (343 4403);
FORCEPROP 1 LAST LOCATION J29
J 0
(325 4300);
DISPLAY 0.723404 (325 4300);
PAINT GREEN (325 4300);
FORCEPROP 0 LASTPIN (1675 3000) $PN 12
J 0
(1685 3010);
DISPLAY 0.680851 (1685 3010);
PAINT MONO (1685 3010);
FORCEPROP 0 LASTPIN (1675 3050) $PN 11
J 0
(1685 3060);
DISPLAY 0.680851 (1685 3060);
PAINT MONO (1685 3060);
FORCEPROP 0 LASTPIN (1675 1950) $PN 105
J 0
(1685 1960);
DISPLAY 0.680851 (1685 1960);
PAINT MONO (1685 1960);
FORCEPROP 0 LASTPIN (1675 2000) $PN 104
J 0
(1685 2010);
DISPLAY 0.680851 (1685 2010);
PAINT MONO (1685 2010);
FORCEPROP 0 LASTPIN (1675 3100) $PN 23
J 0
(1685 3110);
DISPLAY 0.680851 (1685 3110);
PAINT MONO (1685 3110);
FORCEPROP 0 LASTPIN (1675 3150) $PN 22
J 0
(1685 3160);
DISPLAY 0.680851 (1685 3160);
PAINT MONO (1685 3160);
FORCEPROP 0 LASTPIN (1675 2050) $PN 116
J 0
(1685 2060);
DISPLAY 0.680851 (1685 2060);
PAINT MONO (1685 2060);
FORCEPROP 0 LASTPIN (1675 2100) $PN 115
J 0
(1685 2110);
DISPLAY 0.680851 (1685 2110);
PAINT MONO (1685 2110);
FORCEPROP 0 LASTPIN (1675 3200) $PN 34
J 0
(1685 3210);
DISPLAY 0.680851 (1685 3210);
PAINT MONO (1685 3210);
FORCEPROP 0 LASTPIN (1675 3250) $PN 33
J 0
(1685 3260);
DISPLAY 0.680851 (1685 3260);
PAINT MONO (1685 3260);
FORCEPROP 0 LASTPIN (1675 2150) $PN 127
J 0
(1685 2160);
DISPLAY 0.680851 (1685 2160);
PAINT MONO (1685 2160);
FORCEPROP 0 LASTPIN (1675 2200) $PN 126
J 0
(1685 2210);
DISPLAY 0.680851 (1685 2210);
PAINT MONO (1685 2210);
FORCEPROP 0 LASTPIN (1675 3300) $PN 45
J 0
(1685 3310);
DISPLAY 0.680851 (1685 3310);
PAINT MONO (1685 3310);
FORCEPROP 0 LASTPIN (1675 3350) $PN 44
J 0
(1685 3360);
DISPLAY 0.680851 (1685 3360);
PAINT MONO (1685 3360);
FORCEPROP 0 LASTPIN (1675 2250) $PN 138
J 0
(1685 2260);
DISPLAY 0.680851 (1685 2260);
PAINT MONO (1685 2260);
FORCEPROP 0 LASTPIN (1675 2300) $PN 137
J 0
(1685 2310);
DISPLAY 0.680851 (1685 2310);
PAINT MONO (1685 2310);
FORCEPROP 0 LASTPIN (1675 3400) $PN 56
J 0
(1685 3410);
DISPLAY 0.680851 (1685 3410);
PAINT MONO (1685 3410);
FORCEPROP 0 LASTPIN (1675 3450) $PN 55
J 0
(1685 3460);
DISPLAY 0.680851 (1685 3460);
PAINT MONO (1685 3460);
FORCEPROP 0 LASTPIN (1675 2350) $PN 238
J 0
(1685 2360);
DISPLAY 0.680851 (1685 2360);
PAINT MONO (1685 2360);
FORCEPROP 0 LASTPIN (1675 2400) $PN 239
J 0
(1685 2410);
DISPLAY 0.680851 (1685 2410);
PAINT MONO (1685 2410);
FORCEPROP 0 LASTPIN (1675 3500) $PN 156
J 0
(1685 3510);
DISPLAY 0.680851 (1685 3510);
PAINT MONO (1685 3510);
FORCEPROP 0 LASTPIN (1675 3550) $PN 157
J 0
(1685 3560);
DISPLAY 0.680851 (1685 3560);
PAINT MONO (1685 3560);
FORCEPROP 0 LASTPIN (1675 2450) $PN 249
J 0
(1685 2460);
DISPLAY 0.680851 (1685 2460);
PAINT MONO (1685 2460);
FORCEPROP 0 LASTPIN (1675 2500) $PN 250
J 0
(1685 2510);
DISPLAY 0.680851 (1685 2510);
PAINT MONO (1685 2510);
FORCEPROP 0 LASTPIN (1675 3600) $PN 167
J 0
(1685 3610);
DISPLAY 0.680851 (1685 3610);
PAINT MONO (1685 3610);
FORCEPROP 0 LASTPIN (1675 3650) $PN 168
J 0
(1685 3660);
DISPLAY 0.680851 (1685 3660);
PAINT MONO (1685 3660);
FORCEPROP 0 LASTPIN (1675 2550) $PN 260
J 0
(1685 2560);
DISPLAY 0.680851 (1685 2560);
PAINT MONO (1685 2560);
FORCEPROP 0 LASTPIN (1675 2600) $PN 261
J 0
(1685 2610);
DISPLAY 0.680851 (1685 2610);
PAINT MONO (1685 2610);
FORCEPROP 0 LASTPIN (1675 3700) $PN 178
J 0
(1685 3710);
DISPLAY 0.680851 (1685 3710);
PAINT MONO (1685 3710);
FORCEPROP 0 LASTPIN (1675 3750) $PN 179
J 0
(1685 3760);
DISPLAY 0.680851 (1685 3760);
PAINT MONO (1685 3760);
FORCEPROP 0 LASTPIN (1675 2650) $PN 271
J 0
(1685 2660);
DISPLAY 0.680851 (1685 2660);
PAINT MONO (1685 2660);
FORCEPROP 0 LASTPIN (1675 2700) $PN 272
J 0
(1685 2710);
DISPLAY 0.680851 (1685 2710);
PAINT MONO (1685 2710);
FORCEPROP 0 LASTPIN (1675 3800) $PN 189
J 0
(1685 3810);
DISPLAY 0.680851 (1685 3810);
PAINT MONO (1685 3810);
FORCEPROP 0 LASTPIN (1675 3850) $PN 190
J 0
(1685 3860);
DISPLAY 0.680851 (1685 3860);
PAINT MONO (1685 3860);
FORCEPROP 0 LASTPIN (1675 2750) $PN 282
J 0
(1685 2760);
DISPLAY 0.680851 (1685 2760);
PAINT MONO (1685 2760);
FORCEPROP 0 LASTPIN (1675 2800) $PN 283
J 0
(1685 2810);
DISPLAY 0.680851 (1685 2810);
PAINT MONO (1685 2810);
FORCEPROP 0 LASTPIN (1675 3900) $PN 200
J 0
(1685 3910);
DISPLAY 0.680851 (1685 3910);
PAINT MONO (1685 3910);
FORCEPROP 0 LASTPIN (1675 3950) $PN 201
J 0
(1685 3960);
DISPLAY 0.680851 (1685 3960);
PAINT MONO (1685 3960);
FORCEPROP 0 LASTPIN (1675 2850) $PN 94
J 0
(1685 2860);
DISPLAY 0.680851 (1685 2860);
PAINT MONO (1685 2860);
FORCEPROP 0 LASTPIN (1675 2900) $PN 93
J 0
(1685 2910);
DISPLAY 0.680851 (1685 2910);
PAINT MONO (1685 2910);
FORCEPROP 1 LAST NEEDS_NO_SIZE TRUE
J 0
(925 2950);
DISPLAY 0.723404 (925 2950);
PAINT GREEN (925 2950);
DISPLAY INVISIBLE (925 2950);
FORCEPROP 1 LAST CDS_LMAN_SYM_OUTLINE -600,1150,600,-1150
J 0
(925 2950);
DISPLAY 0.468085 (925 2950);
PAINT GREEN (925 2950);
DISPLAY INVISIBLE (925 2950);
FORCEPROP 2 LAST CDS_LIB pure_quanta
J 0
(925 2950);
DISPLAY INVISIBLE (925 2950);
FORCEPROP 1 LAST PATH I180
J 0
(925 2950);
DISPLAY 0.723404 (925 2950);
PAINT GREEN (925 2950);
DISPLAY INVISIBLE (925 2950);
FORCEPROP 0 LAST $SEC 2
J 0
(350 4475);
DISPLAY 0.680851 (350 4475);
PAINT MONO (350 4475);
DISPLAY INVISIBLE (350 4475);
FORCEPROP 0 LAST CDS_SEC 2
J 0
(350 4475);
DISPLAY 1.021277 (350 4475);
DISPLAY INVISIBLE (350 4475);
FORCEADD OFFPAGE..1
(-2325 1175);
FORCEPROP 2 LAST $XR7 113 
J 0
(-3417 1175);
DISPLAY 0.638298 (-3417 1175);
PAINT MONO (-3417 1175);
FORCEPROP 2 LAST $XR6 112 
J 0
(-3297 1175);
DISPLAY 0.638298 (-3297 1175);
PAINT MONO (-3297 1175);
FORCEPROP 2 LAST $XR5 111 
J 0
(-3177 1175);
DISPLAY 0.638298 (-3177 1175);
PAINT MONO (-3177 1175);
FORCEPROP 2 LAST $XR4 109 
J 0
(-3057 1175);
DISPLAY 0.638298 (-3057 1175);
PAINT MONO (-3057 1175);
FORCEPROP 2 LAST $XR3 108 
J 0
(-2937 1175);
DISPLAY 0.638298 (-2937 1175);
PAINT MONO (-2937 1175);
FORCEPROP 2 LAST $XR2 107 
J 0
(-2817 1175);
DISPLAY 0.638298 (-2817 1175);
PAINT MONO (-2817 1175);
FORCEPROP 2 LAST $XR1 106 
J 0
(-2697 1175);
DISPLAY 0.638298 (-2697 1175);
PAINT MONO (-2697 1175);
FORCEPROP 2 LAST $XR0 230 
J 0
(-2577 1175);
DISPLAY 0.638298 (-2577 1175);
PAINT MONO (-2577 1175);
FORCEPROP 2 LAST CDS_LIB standard
J 2
(-2325 1175);
DISPLAY INVISIBLE (-2325 1175);
FORCEPROP 1 LAST OFFPAGE TRUE
J 0
(-2000 1050);
DISPLAY 0.872340 (-2000 1050);
DISPLAY INVISIBLE (-2000 1050);
FORCEPROP 1 LAST COMMENT_BODY TRUE
J 0
(-2200 1075);
DISPLAY 0.872340 (-2200 1075);
PAINT GREEN (-2200 1075);
DISPLAY INVISIBLE (-2200 1075);
FORCEPROP 2 LAST PATH I181
J 2
(-2500 1250);
DISPLAY 1.021277 (-2500 1250);
DISPLAY INVISIBLE (-2500 1250);
FORCEADD Q_RES..1
(-3575 1250);
FORCEPROP 1 LAST PART_NUMBER CS04992FB07
J 0
(-3475 1225);
DISPLAY 0.404255 (-3475 1225);
DISPLAY INVISIBLE (-3475 1225);
FORCEPROP 1 LAST MATERIAL CHIP
J 0
(-3750 1225);
DISPLAY 0.404255 (-3750 1225);
FORCEPROP 1 LAST VALUE 49.9
J 2
(-3350 1250);
DISPLAY 0.510638 (-3350 1250);
FORCEPROP 1 LAST $LOCATION R3903
J 0
(-3800 1250);
DISPLAY 0.638298 (-3800 1250);
FORCEPROP 1 LASTPIN (-3675 1250) $PN 1
J 0
(-3663 1262);
DISPLAY 0.787234 (-3663 1262);
PAINT MONO (-3663 1262);
FORCEPROP 1 LASTPIN (-3475 1250) $PN 2
J 0
(-3513 1262);
DISPLAY 0.787234 (-3513 1262);
PAINT MONO (-3513 1262);
FORCEPROP 2 LAST CDS_LIB pure_quanta
J 0
(-3575 1250);
DISPLAY INVISIBLE (-3575 1250);
FORCEPROP 1 LAST PACK_TYPE 0402LF
J 0
(-3275 1250);
DISPLAY 0.510638 (-3275 1250);
DISPLAY INVISIBLE (-3275 1250);
FORCEPROP 1 LAST TOLERANCE 1%
J 0
(-3350 1250);
DISPLAY 0.510638 (-3350 1250);
DISPLAY INVISIBLE (-3350 1250);
FORCEPROP 1 LAST WATTAGE 1/16W
J 2
(-3275 1200);
DISPLAY 0.404255 (-3275 1200);
DISPLAY INVISIBLE (-3275 1200);
FORCEPROP 1 LAST PATH I182
J 0
(-3625 1400);
DISPLAY 0.978723 (-3625 1400);
PAINT WHITE (-3625 1400);
DISPLAY INVISIBLE (-3625 1400);
FORCEPROP 0 LAST CDS_LOCATION R3903
J 0
(-3725 1300);
DISPLAY 1.021277 (-3725 1300);
DISPLAY INVISIBLE (-3725 1300);
FORCEPROP 0 LAST $SEC 1
J 0
(-3725 1300);
DISPLAY 0.680851 (-3725 1300);
PAINT MONO (-3725 1300);
DISPLAY INVISIBLE (-3725 1300);
FORCEPROP 0 LAST CDS_SEC 1
J 0
(-3725 1300);
DISPLAY 1.021277 (-3725 1300);
DISPLAY INVISIBLE (-3725 1300);
FORCEADD OFFPAGE..1
(-3500 3000);
FORCEPROP 2 LAST $XR0 57 
J 0
(-3721 3000);
DISPLAY 0.638298 (-3721 3000);
PAINT MONO (-3721 3000);
FORCEPROP 2 LAST CDS_LIB standard
J 0
(-3500 3000);
PAINT MONO (-3500 3000);
DISPLAY INVISIBLE (-3500 3000);
FORCEPROP 1 LAST OFFPAGE TRUE
J 0
(-3175 2875);
DISPLAY 0.872340 (-3175 2875);
DISPLAY INVISIBLE (-3175 2875);
FORCEPROP 1 LAST COMMENT_BODY TRUE
J 0
(-3375 2900);
DISPLAY 0.872340 (-3375 2900);
PAINT GREEN (-3375 2900);
DISPLAY INVISIBLE (-3375 2900);
FORCEPROP 2 LAST PATH I19
J 0
(-3450 3075);
DISPLAY 1.021277 (-3450 3075);
DISPLAY INVISIBLE (-3450 3075);
FORCEADD OFFPAGE..2
R 2
(-3500 0);
FORCEPROP 2 LAST $XR0 110 
J 0
(-3755 0);
DISPLAY 0.638298 (-3755 0);
PAINT MONO (-3755 0);
FORCEPROP 2 LAST CDS_LIB standard
J 0
(-3500 0);
PAINT MONO (-3500 0);
DISPLAY INVISIBLE (-3500 0);
FORCEPROP 1 LAST OFFPAGE TRUE
J 2
(-3825 -125);
DISPLAY 0.872340 (-3825 -125);
DISPLAY INVISIBLE (-3825 -125);
FORCEPROP 1 LAST COMMENT_BODY TRUE
J 2
(-3455 -95);
DISPLAY 0.872340 (-3455 -95);
PAINT GREEN (-3455 -95);
DISPLAY INVISIBLE (-3455 -95);
FORCEPROP 2 LAST PATH I2
J 0
(-3450 75);
DISPLAY 1.021277 (-3450 75);
DISPLAY INVISIBLE (-3450 75);
FORCEADD OFFPAGE..1
(-3500 3100);
FORCEPROP 2 LAST $XR1 111 
J 0
(-3841 3100);
DISPLAY 0.638298 (-3841 3100);
PAINT MONO (-3841 3100);
FORCEPROP 2 LAST $XR0 57 
J 0
(-3721 3100);
DISPLAY 0.638298 (-3721 3100);
PAINT MONO (-3721 3100);
FORCEPROP 2 LAST CDS_LIB standard
J 0
(-3500 3100);
PAINT MONO (-3500 3100);
DISPLAY INVISIBLE (-3500 3100);
FORCEPROP 1 LAST OFFPAGE TRUE
J 0
(-3175 2975);
DISPLAY 0.872340 (-3175 2975);
DISPLAY INVISIBLE (-3175 2975);
FORCEPROP 1 LAST COMMENT_BODY TRUE
J 0
(-3375 3000);
DISPLAY 0.872340 (-3375 3000);
PAINT GREEN (-3375 3000);
DISPLAY INVISIBLE (-3375 3000);
FORCEPROP 2 LAST PATH I20
J 0
(-3450 3175);
DISPLAY 1.021277 (-3450 3175);
DISPLAY INVISIBLE (-3450 3175);
FORCEADD OFFPAGE..1
(-3500 3575);
FORCEPROP 2 LAST $XR1 111 
J 0
(-3841 3575);
DISPLAY 0.638298 (-3841 3575);
PAINT MONO (-3841 3575);
FORCEPROP 2 LAST $XR0 57 
J 0
(-3721 3575);
DISPLAY 0.638298 (-3721 3575);
PAINT MONO (-3721 3575);
FORCEPROP 2 LAST CDS_LIB standard
J 0
(-3500 3575);
PAINT MONO (-3500 3575);
DISPLAY INVISIBLE (-3500 3575);
FORCEPROP 1 LAST OFFPAGE TRUE
J 0
(-3175 3450);
DISPLAY 0.872340 (-3175 3450);
DISPLAY INVISIBLE (-3175 3450);
FORCEPROP 1 LAST COMMENT_BODY TRUE
J 0
(-3375 3475);
DISPLAY 0.872340 (-3375 3475);
PAINT GREEN (-3375 3475);
DISPLAY INVISIBLE (-3375 3475);
FORCEPROP 2 LAST PATH I21
J 0
(-3450 3650);
DISPLAY 1.021277 (-3450 3650);
DISPLAY INVISIBLE (-3450 3650);
FORCEADD VCC_CORE..1
(-3400 1825);
FORCEPROP 3 LASTPIN (-3400 1775) SIG_NAME P3V3_AUX\g
J 0
(-3390 1785);
DISPLAY 0.659574 (-3390 1785);
PAINT MONO (-3390 1785);
DISPLAY INVISIBLE (-3390 1785);
FORCEPROP 1 LAST HDL_POWER P3V3_AUX
J 1
(-3400 1875);
DISPLAY 1.148936 (-3400 1875);
PAINT GREEN (-3400 1875);
FORCEPROP 2 LAST CDS_LIB logical_power
J 0
(-3400 1825);
PAINT MONO (-3400 1825);
DISPLAY INVISIBLE (-3400 1825);
FORCEPROP 1 LAST PATH I22
J 0
(-3350 1850);
DISPLAY 0.872340 (-3350 1850);
PAINT AQUA (-3350 1850);
DISPLAY INVISIBLE (-3350 1850);
FORCEADD TAP..1
R 2
(-2575 1800);
FORCEPROP 3 LASTPIN (-2525 1800) SIG_NAME M_G_CPU1_SB_CB<1>
J 0
(-2515 1810);
DISPLAY 0.659574 (-2515 1810);
PAINT MONO (-2515 1810);
DISPLAY INVISIBLE (-2515 1810);
FORCEPROP 1 LASTPIN (-2525 1800) BN 1
J 2
(-2513 1808);
DISPLAY 0.680851 (-2513 1808);
PAINT GREEN (-2513 1808);
FORCEPROP 2 LAST CDS_LIB standard
J 0
(-2575 1800);
DISPLAY INVISIBLE (-2575 1800);
FORCEPROP 1 LAST BODY_TYPE PLUMBING
J 2
(-2575 1850);
DISPLAY 0.872340 (-2575 1850);
PAINT GREEN (-2575 1850);
DISPLAY INVISIBLE (-2575 1850);
FORCEPROP 1 LAST HDL_TAP TRUE
J 2
(-2900 1675);
DISPLAY 0.872340 (-2900 1675);
DISPLAY INVISIBLE (-2900 1675);
FORCEPROP 1 LAST PATH I23
J 2
(-2573 1800);
DISPLAY 0.872340 (-2573 1800);
PAINT GREEN (-2573 1800);
DISPLAY INVISIBLE (-2573 1800);
FORCEADD TAP..1
R 2
(-2575 1850);
FORCEPROP 3 LASTPIN (-2525 1850) SIG_NAME M_G_CPU1_SB_CB<2>
J 0
(-2515 1860);
DISPLAY 0.659574 (-2515 1860);
PAINT MONO (-2515 1860);
DISPLAY INVISIBLE (-2515 1860);
FORCEPROP 1 LASTPIN (-2525 1850) BN 2
J 2
(-2513 1858);
DISPLAY 0.680851 (-2513 1858);
PAINT GREEN (-2513 1858);
FORCEPROP 2 LAST CDS_LIB standard
J 0
(-2575 1850);
DISPLAY INVISIBLE (-2575 1850);
FORCEPROP 1 LAST BODY_TYPE PLUMBING
J 2
(-2575 1900);
DISPLAY 0.872340 (-2575 1900);
PAINT GREEN (-2575 1900);
DISPLAY INVISIBLE (-2575 1900);
FORCEPROP 1 LAST HDL_TAP TRUE
J 2
(-2900 1725);
DISPLAY 0.872340 (-2900 1725);
DISPLAY INVISIBLE (-2900 1725);
FORCEPROP 1 LAST PATH I24
J 2
(-2573 1850);
DISPLAY 0.872340 (-2573 1850);
PAINT GREEN (-2573 1850);
DISPLAY INVISIBLE (-2573 1850);
FORCEADD TAP..1
R 2
(-2575 1750);
FORCEPROP 3 LASTPIN (-2525 1750) SIG_NAME M_G_CPU1_SB_CB<0>
J 0
(-2515 1760);
DISPLAY 0.659574 (-2515 1760);
PAINT MONO (-2515 1760);
DISPLAY INVISIBLE (-2515 1760);
FORCEPROP 1 LASTPIN (-2525 1750) BN 0
J 2
(-2513 1758);
DISPLAY 0.680851 (-2513 1758);
PAINT GREEN (-2513 1758);
FORCEPROP 2 LAST CDS_LIB standard
J 0
(-2575 1750);
PAINT MONO (-2575 1750);
DISPLAY INVISIBLE (-2575 1750);
FORCEPROP 1 LAST BODY_TYPE PLUMBING
J 2
(-2575 1800);
DISPLAY 0.872340 (-2575 1800);
PAINT GREEN (-2575 1800);
DISPLAY INVISIBLE (-2575 1800);
FORCEPROP 1 LAST HDL_TAP TRUE
J 2
(-2900 1625);
DISPLAY 0.872340 (-2900 1625);
DISPLAY INVISIBLE (-2900 1625);
FORCEPROP 1 LAST PATH I25
J 2
(-2573 1750);
DISPLAY 0.872340 (-2573 1750);
PAINT GREEN (-2573 1750);
DISPLAY INVISIBLE (-2573 1750);
FORCEADD TAP..1
R 2
(-2575 1900);
FORCEPROP 3 LASTPIN (-2525 1900) SIG_NAME M_G_CPU1_SB_CB<3>
J 0
(-2515 1910);
DISPLAY 0.659574 (-2515 1910);
PAINT MONO (-2515 1910);
DISPLAY INVISIBLE (-2515 1910);
FORCEPROP 1 LASTPIN (-2525 1900) BN 3
J 2
(-2513 1908);
DISPLAY 0.680851 (-2513 1908);
PAINT GREEN (-2513 1908);
FORCEPROP 2 LAST CDS_LIB standard
J 0
(-2575 1900);
DISPLAY INVISIBLE (-2575 1900);
FORCEPROP 1 LAST BODY_TYPE PLUMBING
J 2
(-2575 1950);
DISPLAY 0.872340 (-2575 1950);
PAINT GREEN (-2575 1950);
DISPLAY INVISIBLE (-2575 1950);
FORCEPROP 1 LAST HDL_TAP TRUE
J 2
(-2900 1775);
DISPLAY 0.872340 (-2900 1775);
DISPLAY INVISIBLE (-2900 1775);
FORCEPROP 1 LAST PATH I26
J 2
(-2573 1900);
DISPLAY 0.872340 (-2573 1900);
PAINT GREEN (-2573 1900);
DISPLAY INVISIBLE (-2573 1900);
FORCEADD TAP..1
R 2
(-2575 1950);
FORCEPROP 3 LASTPIN (-2525 1950) SIG_NAME M_G_CPU1_SB_CB<4>
J 0
(-2515 1960);
DISPLAY 0.659574 (-2515 1960);
PAINT MONO (-2515 1960);
DISPLAY INVISIBLE (-2515 1960);
FORCEPROP 1 LASTPIN (-2525 1950) BN 4
J 2
(-2513 1958);
DISPLAY 0.680851 (-2513 1958);
PAINT GREEN (-2513 1958);
FORCEPROP 2 LAST CDS_LIB standard
J 0
(-2575 1950);
DISPLAY INVISIBLE (-2575 1950);
FORCEPROP 1 LAST BODY_TYPE PLUMBING
J 2
(-2575 2000);
DISPLAY 0.872340 (-2575 2000);
PAINT GREEN (-2575 2000);
DISPLAY INVISIBLE (-2575 2000);
FORCEPROP 1 LAST HDL_TAP TRUE
J 2
(-2900 1825);
DISPLAY 0.872340 (-2900 1825);
DISPLAY INVISIBLE (-2900 1825);
FORCEPROP 1 LAST PATH I27
J 2
(-2573 1950);
DISPLAY 0.872340 (-2573 1950);
PAINT GREEN (-2573 1950);
DISPLAY INVISIBLE (-2573 1950);
FORCEADD TAP..1
R 2
(-2575 2000);
FORCEPROP 3 LASTPIN (-2525 2000) SIG_NAME M_G_CPU1_SB_CB<5>
J 0
(-2515 2010);
DISPLAY 0.659574 (-2515 2010);
PAINT MONO (-2515 2010);
DISPLAY INVISIBLE (-2515 2010);
FORCEPROP 1 LASTPIN (-2525 2000) BN 5
J 2
(-2513 2008);
DISPLAY 0.680851 (-2513 2008);
PAINT GREEN (-2513 2008);
FORCEPROP 2 LAST CDS_LIB standard
J 0
(-2575 2000);
DISPLAY INVISIBLE (-2575 2000);
FORCEPROP 1 LAST BODY_TYPE PLUMBING
J 2
(-2575 2050);
DISPLAY 0.872340 (-2575 2050);
PAINT GREEN (-2575 2050);
DISPLAY INVISIBLE (-2575 2050);
FORCEPROP 1 LAST HDL_TAP TRUE
J 2
(-2900 1875);
DISPLAY 0.872340 (-2900 1875);
DISPLAY INVISIBLE (-2900 1875);
FORCEPROP 1 LAST PATH I28
J 2
(-2573 2000);
DISPLAY 0.872340 (-2573 2000);
PAINT GREEN (-2573 2000);
DISPLAY INVISIBLE (-2573 2000);
FORCEADD TAP..1
R 2
(-2575 2050);
FORCEPROP 3 LASTPIN (-2525 2050) SIG_NAME M_G_CPU1_SB_CB<6>
J 0
(-2515 2060);
DISPLAY 0.659574 (-2515 2060);
PAINT MONO (-2515 2060);
DISPLAY INVISIBLE (-2515 2060);
FORCEPROP 1 LASTPIN (-2525 2050) BN 6
J 2
(-2513 2058);
DISPLAY 0.680851 (-2513 2058);
PAINT GREEN (-2513 2058);
FORCEPROP 2 LAST CDS_LIB standard
J 0
(-2575 2050);
DISPLAY INVISIBLE (-2575 2050);
FORCEPROP 1 LAST BODY_TYPE PLUMBING
J 2
(-2575 2100);
DISPLAY 0.872340 (-2575 2100);
PAINT GREEN (-2575 2100);
DISPLAY INVISIBLE (-2575 2100);
FORCEPROP 1 LAST HDL_TAP TRUE
J 2
(-2900 1925);
DISPLAY 0.872340 (-2900 1925);
DISPLAY INVISIBLE (-2900 1925);
FORCEPROP 1 LAST PATH I29
J 2
(-2573 2050);
DISPLAY 0.872340 (-2573 2050);
PAINT GREEN (-2573 2050);
DISPLAY INVISIBLE (-2573 2050);
FORCEADD OFFPAGE..2
R 2
(-3500 550);
FORCEPROP 2 LAST $XR0 57 
J 0
(-3724 550);
DISPLAY 0.638298 (-3724 550);
PAINT MONO (-3724 550);
FORCEPROP 2 LAST CDS_LIB standard
J 0
(-3500 550);
PAINT MONO (-3500 550);
DISPLAY INVISIBLE (-3500 550);
FORCEPROP 1 LAST OFFPAGE TRUE
J 2
(-3825 425);
DISPLAY 0.872340 (-3825 425);
DISPLAY INVISIBLE (-3825 425);
FORCEPROP 1 LAST COMMENT_BODY TRUE
J 2
(-3455 455);
DISPLAY 0.872340 (-3455 455);
PAINT GREEN (-3455 455);
DISPLAY INVISIBLE (-3455 455);
FORCEPROP 2 LAST PATH I3
J 0
(-3450 625);
DISPLAY 1.021277 (-3450 625);
DISPLAY INVISIBLE (-3450 625);
FORCEADD TAP..1
R 2
(-2575 2100);
FORCEPROP 3 LASTPIN (-2525 2100) SIG_NAME M_G_CPU1_SB_CB<7>
J 0
(-2515 2110);
DISPLAY 0.659574 (-2515 2110);
PAINT MONO (-2515 2110);
DISPLAY INVISIBLE (-2515 2110);
FORCEPROP 1 LASTPIN (-2525 2100) BN 7
J 2
(-2513 2108);
DISPLAY 0.680851 (-2513 2108);
PAINT GREEN (-2513 2108);
FORCEPROP 2 LAST CDS_LIB standard
J 0
(-2575 2100);
DISPLAY INVISIBLE (-2575 2100);
FORCEPROP 1 LAST BODY_TYPE PLUMBING
J 2
(-2575 2150);
DISPLAY 0.872340 (-2575 2150);
PAINT GREEN (-2575 2150);
DISPLAY INVISIBLE (-2575 2150);
FORCEPROP 1 LAST HDL_TAP TRUE
J 2
(-2900 1975);
DISPLAY 0.872340 (-2900 1975);
DISPLAY INVISIBLE (-2900 1975);
FORCEPROP 1 LAST PATH I30
J 2
(-2573 2100);
DISPLAY 0.872340 (-2573 2100);
PAINT GREEN (-2573 2100);
DISPLAY INVISIBLE (-2573 2100);
FORCEADD TAP..1
R 2
(-2575 2300);
FORCEPROP 3 LASTPIN (-2525 2300) SIG_NAME M_G_CPU1_SA_CB<2>
J 0
(-2515 2310);
DISPLAY 0.659574 (-2515 2310);
PAINT MONO (-2515 2310);
DISPLAY INVISIBLE (-2515 2310);
FORCEPROP 1 LASTPIN (-2525 2300) BN 2
J 2
(-2513 2308);
DISPLAY 0.680851 (-2513 2308);
PAINT GREEN (-2513 2308);
FORCEPROP 2 LAST CDS_LIB standard
J 0
(-2575 2300);
DISPLAY INVISIBLE (-2575 2300);
FORCEPROP 1 LAST BODY_TYPE PLUMBING
J 2
(-2575 2350);
DISPLAY 0.872340 (-2575 2350);
PAINT GREEN (-2575 2350);
DISPLAY INVISIBLE (-2575 2350);
FORCEPROP 1 LAST HDL_TAP TRUE
J 2
(-2900 2175);
DISPLAY 0.872340 (-2900 2175);
DISPLAY INVISIBLE (-2900 2175);
FORCEPROP 1 LAST PATH I31
J 2
(-2573 2300);
DISPLAY 0.872340 (-2573 2300);
PAINT GREEN (-2573 2300);
DISPLAY INVISIBLE (-2573 2300);
FORCEADD TAP..1
R 2
(-2575 2350);
FORCEPROP 3 LASTPIN (-2525 2350) SIG_NAME M_G_CPU1_SA_CB<3>
J 0
(-2515 2360);
DISPLAY 0.659574 (-2515 2360);
PAINT MONO (-2515 2360);
DISPLAY INVISIBLE (-2515 2360);
FORCEPROP 1 LASTPIN (-2525 2350) BN 3
J 2
(-2513 2358);
DISPLAY 0.680851 (-2513 2358);
PAINT GREEN (-2513 2358);
FORCEPROP 2 LAST CDS_LIB standard
J 0
(-2575 2350);
DISPLAY INVISIBLE (-2575 2350);
FORCEPROP 1 LAST BODY_TYPE PLUMBING
J 2
(-2575 2400);
DISPLAY 0.872340 (-2575 2400);
PAINT GREEN (-2575 2400);
DISPLAY INVISIBLE (-2575 2400);
FORCEPROP 1 LAST HDL_TAP TRUE
J 2
(-2900 2225);
DISPLAY 0.872340 (-2900 2225);
DISPLAY INVISIBLE (-2900 2225);
FORCEPROP 1 LAST PATH I32
J 2
(-2573 2350);
DISPLAY 0.872340 (-2573 2350);
PAINT GREEN (-2573 2350);
DISPLAY INVISIBLE (-2573 2350);
FORCEADD TAP..1
R 2
(-2575 2250);
FORCEPROP 3 LASTPIN (-2525 2250) SIG_NAME M_G_CPU1_SA_CB<1>
J 0
(-2515 2260);
DISPLAY 0.659574 (-2515 2260);
PAINT MONO (-2515 2260);
DISPLAY INVISIBLE (-2515 2260);
FORCEPROP 1 LASTPIN (-2525 2250) BN 1
J 2
(-2513 2258);
DISPLAY 0.680851 (-2513 2258);
PAINT GREEN (-2513 2258);
FORCEPROP 2 LAST CDS_LIB standard
J 0
(-2575 2250);
DISPLAY INVISIBLE (-2575 2250);
FORCEPROP 1 LAST BODY_TYPE PLUMBING
J 2
(-2575 2300);
DISPLAY 0.872340 (-2575 2300);
PAINT GREEN (-2575 2300);
DISPLAY INVISIBLE (-2575 2300);
FORCEPROP 1 LAST HDL_TAP TRUE
J 2
(-2900 2125);
DISPLAY 0.872340 (-2900 2125);
DISPLAY INVISIBLE (-2900 2125);
FORCEPROP 1 LAST PATH I33
J 2
(-2573 2250);
DISPLAY 0.872340 (-2573 2250);
PAINT GREEN (-2573 2250);
DISPLAY INVISIBLE (-2573 2250);
FORCEADD TAP..1
R 2
(-2575 2200);
FORCEPROP 3 LASTPIN (-2525 2200) SIG_NAME M_G_CPU1_SA_CB<0>
J 0
(-2515 2210);
DISPLAY 0.659574 (-2515 2210);
PAINT MONO (-2515 2210);
DISPLAY INVISIBLE (-2515 2210);
FORCEPROP 1 LASTPIN (-2525 2200) BN 0
J 2
(-2513 2208);
DISPLAY 0.680851 (-2513 2208);
PAINT GREEN (-2513 2208);
FORCEPROP 2 LAST CDS_LIB standard
J 0
(-2575 2200);
PAINT MONO (-2575 2200);
DISPLAY INVISIBLE (-2575 2200);
FORCEPROP 1 LAST BODY_TYPE PLUMBING
J 2
(-2575 2250);
DISPLAY 0.872340 (-2575 2250);
PAINT GREEN (-2575 2250);
DISPLAY INVISIBLE (-2575 2250);
FORCEPROP 1 LAST HDL_TAP TRUE
J 2
(-2900 2075);
DISPLAY 0.872340 (-2900 2075);
DISPLAY INVISIBLE (-2900 2075);
FORCEPROP 1 LAST PATH I34
J 2
(-2573 2200);
DISPLAY 0.872340 (-2573 2200);
PAINT GREEN (-2573 2200);
DISPLAY INVISIBLE (-2573 2200);
FORCEADD TAP..1
R 2
(-2575 2400);
FORCEPROP 3 LASTPIN (-2525 2400) SIG_NAME M_G_CPU1_SA_CB<4>
J 0
(-2515 2410);
DISPLAY 0.659574 (-2515 2410);
PAINT MONO (-2515 2410);
DISPLAY INVISIBLE (-2515 2410);
FORCEPROP 1 LASTPIN (-2525 2400) BN 4
J 2
(-2513 2408);
DISPLAY 0.680851 (-2513 2408);
PAINT GREEN (-2513 2408);
FORCEPROP 2 LAST CDS_LIB standard
J 0
(-2575 2400);
DISPLAY INVISIBLE (-2575 2400);
FORCEPROP 1 LAST BODY_TYPE PLUMBING
J 2
(-2575 2450);
DISPLAY 0.872340 (-2575 2450);
PAINT GREEN (-2575 2450);
DISPLAY INVISIBLE (-2575 2450);
FORCEPROP 1 LAST HDL_TAP TRUE
J 2
(-2900 2275);
DISPLAY 0.872340 (-2900 2275);
DISPLAY INVISIBLE (-2900 2275);
FORCEPROP 1 LAST PATH I35
J 2
(-2573 2400);
DISPLAY 0.872340 (-2573 2400);
PAINT GREEN (-2573 2400);
DISPLAY INVISIBLE (-2573 2400);
FORCEADD TAP..1
R 2
(-2575 2550);
FORCEPROP 3 LASTPIN (-2525 2550) SIG_NAME M_G_CPU1_SA_CB<7>
J 0
(-2515 2560);
DISPLAY 0.659574 (-2515 2560);
PAINT MONO (-2515 2560);
DISPLAY INVISIBLE (-2515 2560);
FORCEPROP 1 LASTPIN (-2525 2550) BN 7
J 2
(-2513 2558);
DISPLAY 0.680851 (-2513 2558);
PAINT GREEN (-2513 2558);
FORCEPROP 2 LAST CDS_LIB standard
J 0
(-2575 2550);
DISPLAY INVISIBLE (-2575 2550);
FORCEPROP 1 LAST BODY_TYPE PLUMBING
J 2
(-2575 2600);
DISPLAY 0.872340 (-2575 2600);
PAINT GREEN (-2575 2600);
DISPLAY INVISIBLE (-2575 2600);
FORCEPROP 1 LAST HDL_TAP TRUE
J 2
(-2900 2425);
DISPLAY 0.872340 (-2900 2425);
DISPLAY INVISIBLE (-2900 2425);
FORCEPROP 1 LAST PATH I36
J 2
(-2573 2550);
DISPLAY 0.872340 (-2573 2550);
PAINT GREEN (-2573 2550);
DISPLAY INVISIBLE (-2573 2550);
FORCEADD TAP..1
R 2
(-2575 2500);
FORCEPROP 3 LASTPIN (-2525 2500) SIG_NAME M_G_CPU1_SA_CB<6>
J 0
(-2515 2510);
DISPLAY 0.659574 (-2515 2510);
PAINT MONO (-2515 2510);
DISPLAY INVISIBLE (-2515 2510);
FORCEPROP 1 LASTPIN (-2525 2500) BN 6
J 2
(-2513 2508);
DISPLAY 0.680851 (-2513 2508);
PAINT GREEN (-2513 2508);
FORCEPROP 2 LAST CDS_LIB standard
J 0
(-2575 2500);
DISPLAY INVISIBLE (-2575 2500);
FORCEPROP 1 LAST BODY_TYPE PLUMBING
J 2
(-2575 2550);
DISPLAY 0.872340 (-2575 2550);
PAINT GREEN (-2575 2550);
DISPLAY INVISIBLE (-2575 2550);
FORCEPROP 1 LAST HDL_TAP TRUE
J 2
(-2900 2375);
DISPLAY 0.872340 (-2900 2375);
DISPLAY INVISIBLE (-2900 2375);
FORCEPROP 1 LAST PATH I37
J 2
(-2573 2500);
DISPLAY 0.872340 (-2573 2500);
PAINT GREEN (-2573 2500);
DISPLAY INVISIBLE (-2573 2500);
FORCEADD TAP..1
R 2
(-2575 2450);
FORCEPROP 3 LASTPIN (-2525 2450) SIG_NAME M_G_CPU1_SA_CB<5>
J 0
(-2515 2460);
DISPLAY 0.659574 (-2515 2460);
PAINT MONO (-2515 2460);
DISPLAY INVISIBLE (-2515 2460);
FORCEPROP 1 LASTPIN (-2525 2450) BN 5
J 2
(-2513 2458);
DISPLAY 0.680851 (-2513 2458);
PAINT GREEN (-2513 2458);
FORCEPROP 2 LAST CDS_LIB standard
J 0
(-2575 2450);
DISPLAY INVISIBLE (-2575 2450);
FORCEPROP 1 LAST BODY_TYPE PLUMBING
J 2
(-2575 2500);
DISPLAY 0.872340 (-2575 2500);
PAINT GREEN (-2575 2500);
DISPLAY INVISIBLE (-2575 2500);
FORCEPROP 1 LAST HDL_TAP TRUE
J 2
(-2900 2325);
DISPLAY 0.872340 (-2900 2325);
DISPLAY INVISIBLE (-2900 2325);
FORCEPROP 1 LAST PATH I38
J 2
(-2573 2450);
DISPLAY 0.872340 (-2573 2450);
PAINT GREEN (-2573 2450);
DISPLAY INVISIBLE (-2573 2450);
FORCEADD TAP..1
R 2
(-2575 3300);
FORCEPROP 3 LASTPIN (-2525 3300) SIG_NAME M_G_CPU1_SB_CA<1>
J 0
(-2515 3310);
DISPLAY 0.659574 (-2515 3310);
PAINT MONO (-2515 3310);
DISPLAY INVISIBLE (-2515 3310);
FORCEPROP 1 LASTPIN (-2525 3300) BN 1
J 2
(-2513 3308);
DISPLAY 0.680851 (-2513 3308);
PAINT GREEN (-2513 3308);
FORCEPROP 2 LAST CDS_LIB standard
J 0
(-2575 3300);
DISPLAY INVISIBLE (-2575 3300);
FORCEPROP 1 LAST BODY_TYPE PLUMBING
J 2
(-2575 3350);
DISPLAY 0.872340 (-2575 3350);
PAINT GREEN (-2575 3350);
DISPLAY INVISIBLE (-2575 3350);
FORCEPROP 1 LAST HDL_TAP TRUE
J 2
(-2900 3175);
DISPLAY 0.872340 (-2900 3175);
DISPLAY INVISIBLE (-2900 3175);
FORCEPROP 1 LAST PATH I39
J 2
(-2573 3300);
DISPLAY 0.872340 (-2573 3300);
PAINT GREEN (-2573 3300);
DISPLAY INVISIBLE (-2573 3300);
FORCEADD OFFPAGE..2
R 2
(-3500 500);
FORCEPROP 2 LAST $XR0 57 
J 0
(-3724 500);
DISPLAY 0.638298 (-3724 500);
PAINT MONO (-3724 500);
FORCEPROP 2 LAST CDS_LIB standard
J 0
(-3500 500);
PAINT MONO (-3500 500);
DISPLAY INVISIBLE (-3500 500);
FORCEPROP 1 LAST OFFPAGE TRUE
J 2
(-3825 375);
DISPLAY 0.872340 (-3825 375);
DISPLAY INVISIBLE (-3825 375);
FORCEPROP 1 LAST COMMENT_BODY TRUE
J 2
(-3455 405);
DISPLAY 0.872340 (-3455 405);
PAINT GREEN (-3455 405);
DISPLAY INVISIBLE (-3455 405);
FORCEPROP 2 LAST PATH I4
J 0
(-3450 575);
DISPLAY 1.021277 (-3450 575);
DISPLAY INVISIBLE (-3450 575);
FORCEADD TAP..1
R 2
(-2575 3350);
FORCEPROP 3 LASTPIN (-2525 3350) SIG_NAME M_G_CPU1_SB_CA<2>
J 0
(-2515 3360);
DISPLAY 0.659574 (-2515 3360);
PAINT MONO (-2515 3360);
DISPLAY INVISIBLE (-2515 3360);
FORCEPROP 1 LASTPIN (-2525 3350) BN 2
J 2
(-2513 3358);
DISPLAY 0.680851 (-2513 3358);
PAINT GREEN (-2513 3358);
FORCEPROP 2 LAST CDS_LIB standard
J 0
(-2575 3350);
DISPLAY INVISIBLE (-2575 3350);
FORCEPROP 1 LAST BODY_TYPE PLUMBING
J 2
(-2575 3400);
DISPLAY 0.872340 (-2575 3400);
PAINT GREEN (-2575 3400);
DISPLAY INVISIBLE (-2575 3400);
FORCEPROP 1 LAST HDL_TAP TRUE
J 2
(-2900 3225);
DISPLAY 0.872340 (-2900 3225);
DISPLAY INVISIBLE (-2900 3225);
FORCEPROP 1 LAST PATH I40
J 2
(-2573 3350);
DISPLAY 0.872340 (-2573 3350);
PAINT GREEN (-2573 3350);
DISPLAY INVISIBLE (-2573 3350);
FORCEADD TAP..1
R 2
(-2575 3400);
FORCEPROP 3 LASTPIN (-2525 3400) SIG_NAME M_G_CPU1_SB_CA<3>
J 0
(-2515 3410);
DISPLAY 0.659574 (-2515 3410);
PAINT MONO (-2515 3410);
DISPLAY INVISIBLE (-2515 3410);
FORCEPROP 1 LASTPIN (-2525 3400) BN 3
J 2
(-2513 3408);
DISPLAY 0.680851 (-2513 3408);
PAINT GREEN (-2513 3408);
FORCEPROP 2 LAST CDS_LIB standard
J 0
(-2575 3400);
DISPLAY INVISIBLE (-2575 3400);
FORCEPROP 1 LAST BODY_TYPE PLUMBING
J 2
(-2575 3450);
DISPLAY 0.872340 (-2575 3450);
PAINT GREEN (-2575 3450);
DISPLAY INVISIBLE (-2575 3450);
FORCEPROP 1 LAST HDL_TAP TRUE
J 2
(-2900 3275);
DISPLAY 0.872340 (-2900 3275);
DISPLAY INVISIBLE (-2900 3275);
FORCEPROP 1 LAST PATH I41
J 2
(-2573 3400);
DISPLAY 0.872340 (-2573 3400);
PAINT GREEN (-2573 3400);
DISPLAY INVISIBLE (-2573 3400);
FORCEADD TAP..1
R 2
(-2575 3250);
FORCEPROP 3 LASTPIN (-2525 3250) SIG_NAME M_G_CPU1_SB_CA<0>
J 0
(-2515 3260);
DISPLAY 0.659574 (-2515 3260);
PAINT MONO (-2515 3260);
DISPLAY INVISIBLE (-2515 3260);
FORCEPROP 1 LASTPIN (-2525 3250) BN 0
J 2
(-2513 3258);
DISPLAY 0.680851 (-2513 3258);
PAINT GREEN (-2513 3258);
FORCEPROP 2 LAST CDS_LIB standard
J 0
(-2575 3250);
DISPLAY INVISIBLE (-2575 3250);
FORCEPROP 1 LAST BODY_TYPE PLUMBING
J 2
(-2575 3300);
DISPLAY 0.872340 (-2575 3300);
PAINT GREEN (-2575 3300);
DISPLAY INVISIBLE (-2575 3300);
FORCEPROP 1 LAST HDL_TAP TRUE
J 2
(-2900 3125);
DISPLAY 0.872340 (-2900 3125);
DISPLAY INVISIBLE (-2900 3125);
FORCEPROP 1 LAST PATH I42
J 2
(-2573 3250);
DISPLAY 0.872340 (-2573 3250);
PAINT GREEN (-2573 3250);
DISPLAY INVISIBLE (-2573 3250);
FORCEADD TAP..1
R 2
(-2575 3450);
FORCEPROP 3 LASTPIN (-2525 3450) SIG_NAME M_G_CPU1_SB_CA<4>
J 0
(-2515 3460);
DISPLAY 0.659574 (-2515 3460);
PAINT MONO (-2515 3460);
DISPLAY INVISIBLE (-2515 3460);
FORCEPROP 1 LASTPIN (-2525 3450) BN 4
J 2
(-2513 3458);
DISPLAY 0.680851 (-2513 3458);
PAINT GREEN (-2513 3458);
FORCEPROP 2 LAST CDS_LIB standard
J 0
(-2575 3450);
DISPLAY INVISIBLE (-2575 3450);
FORCEPROP 1 LAST BODY_TYPE PLUMBING
J 2
(-2575 3500);
DISPLAY 0.872340 (-2575 3500);
PAINT GREEN (-2575 3500);
DISPLAY INVISIBLE (-2575 3500);
FORCEPROP 1 LAST HDL_TAP TRUE
J 2
(-2900 3325);
DISPLAY 0.872340 (-2900 3325);
DISPLAY INVISIBLE (-2900 3325);
FORCEPROP 1 LAST PATH I43
J 2
(-2573 3450);
DISPLAY 0.872340 (-2573 3450);
PAINT GREEN (-2573 3450);
DISPLAY INVISIBLE (-2573 3450);
FORCEADD TAP..1
R 2
(-2575 3500);
FORCEPROP 3 LASTPIN (-2525 3500) SIG_NAME M_G_CPU1_SB_CA<5>
J 0
(-2515 3510);
DISPLAY 0.659574 (-2515 3510);
PAINT MONO (-2515 3510);
DISPLAY INVISIBLE (-2515 3510);
FORCEPROP 1 LASTPIN (-2525 3500) BN 5
J 2
(-2513 3508);
DISPLAY 0.680851 (-2513 3508);
PAINT GREEN (-2513 3508);
FORCEPROP 2 LAST CDS_LIB standard
J 0
(-2575 3500);
DISPLAY INVISIBLE (-2575 3500);
FORCEPROP 1 LAST BODY_TYPE PLUMBING
J 2
(-2575 3550);
DISPLAY 0.872340 (-2575 3550);
PAINT GREEN (-2575 3550);
DISPLAY INVISIBLE (-2575 3550);
FORCEPROP 1 LAST HDL_TAP TRUE
J 2
(-2900 3375);
DISPLAY 0.872340 (-2900 3375);
DISPLAY INVISIBLE (-2900 3375);
FORCEPROP 1 LAST PATH I44
J 2
(-2573 3500);
DISPLAY 0.872340 (-2573 3500);
PAINT GREEN (-2573 3500);
DISPLAY INVISIBLE (-2573 3500);
FORCEADD TAP..1
R 2
(-2575 3550);
FORCEPROP 3 LASTPIN (-2525 3550) SIG_NAME M_G_CPU1_SB_CA<6>
J 0
(-2515 3560);
DISPLAY 0.659574 (-2515 3560);
PAINT MONO (-2515 3560);
DISPLAY INVISIBLE (-2515 3560);
FORCEPROP 1 LASTPIN (-2525 3550) BN 6
J 2
(-2513 3558);
DISPLAY 0.680851 (-2513 3558);
PAINT GREEN (-2513 3558);
FORCEPROP 2 LAST CDS_LIB standard
J 0
(-2575 3550);
DISPLAY INVISIBLE (-2575 3550);
FORCEPROP 1 LAST BODY_TYPE PLUMBING
J 2
(-2575 3600);
DISPLAY 0.872340 (-2575 3600);
PAINT GREEN (-2575 3600);
DISPLAY INVISIBLE (-2575 3600);
FORCEPROP 1 LAST HDL_TAP TRUE
J 2
(-2900 3425);
DISPLAY 0.872340 (-2900 3425);
DISPLAY INVISIBLE (-2900 3425);
FORCEPROP 1 LAST PATH I45
J 2
(-2573 3550);
DISPLAY 0.872340 (-2573 3550);
PAINT GREEN (-2573 3550);
DISPLAY INVISIBLE (-2573 3550);
FORCEADD TAP..1
R 2
(-2575 3650);
FORCEPROP 3 LASTPIN (-2525 3650) SIG_NAME M_G_CPU1_SA_CA<0>
J 0
(-2515 3660);
DISPLAY 0.659574 (-2515 3660);
PAINT MONO (-2515 3660);
DISPLAY INVISIBLE (-2515 3660);
FORCEPROP 1 LASTPIN (-2525 3650) BN 0
J 2
(-2513 3658);
DISPLAY 0.680851 (-2513 3658);
PAINT GREEN (-2513 3658);
FORCEPROP 2 LAST CDS_LIB standard
J 0
(-2575 3650);
DISPLAY INVISIBLE (-2575 3650);
FORCEPROP 1 LAST BODY_TYPE PLUMBING
J 2
(-2575 3700);
DISPLAY 0.872340 (-2575 3700);
PAINT GREEN (-2575 3700);
DISPLAY INVISIBLE (-2575 3700);
FORCEPROP 1 LAST HDL_TAP TRUE
J 2
(-2900 3525);
DISPLAY 0.872340 (-2900 3525);
DISPLAY INVISIBLE (-2900 3525);
FORCEPROP 1 LAST PATH I46
J 2
(-2573 3650);
DISPLAY 0.872340 (-2573 3650);
PAINT GREEN (-2573 3650);
DISPLAY INVISIBLE (-2573 3650);
FORCEADD Q_RES..2
(-2350 -200);
FORCEPROP 1 LAST PART_NUMBER CS35492FB03
J 0
(-2310 -325);
DISPLAY 0.978723 (-2310 -325);
DISPLAY INVISIBLE (-2310 -325);
FORCEPROP 1 LAST VALUE 54.9K
J 0
(-2305 -125);
DISPLAY 0.978723 (-2305 -125);
FORCEPROP 1 LAST WATTAGE 1/16W
J 0
(-2310 -225);
DISPLAY 0.978723 (-2310 -225);
FORCEPROP 1 LAST MATERIAL CHIP
J 0
(-2310 -275);
DISPLAY 0.978723 (-2310 -275);
FORCEPROP 1 LAST TOLERANCE 1%
J 0
(-2305 -175);
DISPLAY 0.978723 (-2305 -175);
FORCEPROP 1 LAST PACK_TYPE 0402LF
J 0
(-2310 -375);
DISPLAY 0.978723 (-2310 -375);
FORCEPROP 1 LAST $LOCATION R75
J 0
(-2305 -75);
DISPLAY 0.978723 (-2305 -75);
FORCEPROP 1 LASTPIN (-2350 -100) $PN 1
J 0
(-2345 -138);
DISPLAY 0.787234 (-2345 -138);
FORCEPROP 1 LASTPIN (-2350 -300) $PN 2
J 0
(-2345 -290);
DISPLAY 0.787234 (-2345 -290);
FORCEPROP 2 LAST CDS_LIB pure_quanta
J 0
(-2350 -200);
PAINT MONO (-2350 -200);
DISPLAY INVISIBLE (-2350 -200);
FORCEPROP 1 LAST PATH I47
J 0
(-2300 -25);
DISPLAY 0.978723 (-2300 -25);
PAINT WHITE (-2300 -25);
DISPLAY INVISIBLE (-2300 -25);
FORCEPROP 1 LAST $LOCATION R75
J 0
(-2300 25);
DISPLAY 1.021277 (-2300 25);
DISPLAY INVISIBLE (-2300 25);
FORCEPROP 2 LAST CDS_LOCATION R75
J 0
(-2300 25);
DISPLAY 1.021277 (-2300 25);
DISPLAY INVISIBLE (-2300 25);
FORCEPROP 2 LAST $SEC 1
J 0
(-2300 25);
DISPLAY 0.680851 (-2300 25);
PAINT MONO (-2300 25);
DISPLAY INVISIBLE (-2300 25);
FORCEPROP 2 LAST CDS_SEC 1
J 0
(-2300 25);
DISPLAY 1.021277 (-2300 25);
DISPLAY INVISIBLE (-2300 25);
FORCEADD TAP..1
(-925 750);
FORCEPROP 3 LASTPIN (-975 750) SIG_NAME M_G_CPU1_SB_DQ<0>
J 0
(-965 760);
DISPLAY 0.659574 (-965 760);
PAINT MONO (-965 760);
DISPLAY INVISIBLE (-965 760);
FORCEPROP 1 LASTPIN (-975 750) BN 0
J 0
(-987 758);
DISPLAY 0.680851 (-987 758);
PAINT GREEN (-987 758);
FORCEPROP 2 LAST CDS_LIB standard
J 0
(-925 750);
PAINT MONO (-925 750);
DISPLAY INVISIBLE (-925 750);
FORCEPROP 1 LAST BODY_TYPE PLUMBING
J 0
(-925 800);
DISPLAY 0.872340 (-925 800);
PAINT GREEN (-925 800);
DISPLAY INVISIBLE (-925 800);
FORCEPROP 1 LAST HDL_TAP TRUE
J 0
(-600 625);
DISPLAY 0.872340 (-600 625);
DISPLAY INVISIBLE (-600 625);
FORCEPROP 1 LAST PATH I48
J 0
(-927 750);
DISPLAY 0.872340 (-927 750);
PAINT GREEN (-927 750);
DISPLAY INVISIBLE (-927 750);
FORCEADD TAP..1
(-925 850);
FORCEPROP 3 LASTPIN (-975 850) SIG_NAME M_G_CPU1_SB_DQ<2>
J 0
(-965 860);
DISPLAY 0.659574 (-965 860);
PAINT MONO (-965 860);
DISPLAY INVISIBLE (-965 860);
FORCEPROP 1 LASTPIN (-975 850) BN 2
J 0
(-987 858);
DISPLAY 0.680851 (-987 858);
PAINT GREEN (-987 858);
FORCEPROP 2 LAST CDS_LIB standard
J 0
(-925 850);
PAINT MONO (-925 850);
DISPLAY INVISIBLE (-925 850);
FORCEPROP 1 LAST BODY_TYPE PLUMBING
J 0
(-925 900);
DISPLAY 0.872340 (-925 900);
PAINT GREEN (-925 900);
DISPLAY INVISIBLE (-925 900);
FORCEPROP 1 LAST HDL_TAP TRUE
J 0
(-600 725);
DISPLAY 0.872340 (-600 725);
DISPLAY INVISIBLE (-600 725);
FORCEPROP 1 LAST PATH I49
J 0
(-927 850);
DISPLAY 0.872340 (-927 850);
PAINT GREEN (-927 850);
DISPLAY INVISIBLE (-927 850);
FORCEADD OFFPAGE..3
R 2
(-3500 1100);
FORCEPROP 2 LAST $XR0 114 
J 0
(-3780 1100);
DISPLAY 0.638298 (-3780 1100);
PAINT MONO (-3780 1100);
FORCEPROP 2 LAST CDS_LIB standard
J 0
(-3500 1100);
PAINT MONO (-3500 1100);
DISPLAY INVISIBLE (-3500 1100);
FORCEPROP 1 LAST OFFPAGE TRUE
J 2
(-3825 975);
DISPLAY 0.872340 (-3825 975);
DISPLAY INVISIBLE (-3825 975);
FORCEPROP 1 LAST COMMENT_BODY TRUE
J 2
(-3450 1000);
DISPLAY 0.872340 (-3450 1000);
PAINT GREEN (-3450 1000);
DISPLAY INVISIBLE (-3450 1000);
FORCEPROP 2 LAST PATH I5
J 0
(-3450 1175);
DISPLAY 1.021277 (-3450 1175);
DISPLAY INVISIBLE (-3450 1175);
FORCEADD TAP..1
(-925 800);
FORCEPROP 3 LASTPIN (-975 800) SIG_NAME M_G_CPU1_SB_DQ<1>
J 0
(-965 810);
DISPLAY 0.659574 (-965 810);
PAINT MONO (-965 810);
DISPLAY INVISIBLE (-965 810);
FORCEPROP 1 LASTPIN (-975 800) BN 1
J 0
(-987 808);
DISPLAY 0.680851 (-987 808);
PAINT GREEN (-987 808);
FORCEPROP 2 LAST CDS_LIB standard
J 0
(-925 800);
PAINT MONO (-925 800);
DISPLAY INVISIBLE (-925 800);
FORCEPROP 1 LAST BODY_TYPE PLUMBING
J 0
(-925 850);
DISPLAY 0.872340 (-925 850);
PAINT GREEN (-925 850);
DISPLAY INVISIBLE (-925 850);
FORCEPROP 1 LAST HDL_TAP TRUE
J 0
(-600 675);
DISPLAY 0.872340 (-600 675);
DISPLAY INVISIBLE (-600 675);
FORCEPROP 1 LAST PATH I50
J 0
(-927 800);
DISPLAY 0.872340 (-927 800);
PAINT GREEN (-927 800);
DISPLAY INVISIBLE (-927 800);
FORCEADD TAP..1
(-925 900);
FORCEPROP 3 LASTPIN (-975 900) SIG_NAME M_G_CPU1_SB_DQ<3>
J 0
(-965 910);
DISPLAY 0.659574 (-965 910);
PAINT MONO (-965 910);
DISPLAY INVISIBLE (-965 910);
FORCEPROP 1 LASTPIN (-975 900) BN 3
J 0
(-987 908);
DISPLAY 0.680851 (-987 908);
PAINT GREEN (-987 908);
FORCEPROP 2 LAST CDS_LIB standard
J 0
(-925 900);
PAINT MONO (-925 900);
DISPLAY INVISIBLE (-925 900);
FORCEPROP 1 LAST BODY_TYPE PLUMBING
J 0
(-925 950);
DISPLAY 0.872340 (-925 950);
PAINT GREEN (-925 950);
DISPLAY INVISIBLE (-925 950);
FORCEPROP 1 LAST HDL_TAP TRUE
J 0
(-600 775);
DISPLAY 0.872340 (-600 775);
DISPLAY INVISIBLE (-600 775);
FORCEPROP 1 LAST PATH I51
J 0
(-927 900);
DISPLAY 0.872340 (-927 900);
PAINT GREEN (-927 900);
DISPLAY INVISIBLE (-927 900);
FORCEADD TAP..1
(-925 950);
FORCEPROP 3 LASTPIN (-975 950) SIG_NAME M_G_CPU1_SB_DQ<4>
J 0
(-965 960);
DISPLAY 0.659574 (-965 960);
PAINT MONO (-965 960);
DISPLAY INVISIBLE (-965 960);
FORCEPROP 1 LASTPIN (-975 950) BN 4
J 0
(-987 958);
DISPLAY 0.680851 (-987 958);
PAINT GREEN (-987 958);
FORCEPROP 2 LAST CDS_LIB standard
J 0
(-925 950);
PAINT MONO (-925 950);
DISPLAY INVISIBLE (-925 950);
FORCEPROP 1 LAST BODY_TYPE PLUMBING
J 0
(-925 1000);
DISPLAY 0.872340 (-925 1000);
PAINT GREEN (-925 1000);
DISPLAY INVISIBLE (-925 1000);
FORCEPROP 1 LAST HDL_TAP TRUE
J 0
(-600 825);
DISPLAY 0.872340 (-600 825);
DISPLAY INVISIBLE (-600 825);
FORCEPROP 1 LAST PATH I52
J 0
(-927 950);
DISPLAY 0.872340 (-927 950);
PAINT GREEN (-927 950);
DISPLAY INVISIBLE (-927 950);
FORCEADD TAP..1
(-925 1000);
FORCEPROP 3 LASTPIN (-975 1000) SIG_NAME M_G_CPU1_SB_DQ<5>
J 0
(-965 1010);
DISPLAY 0.659574 (-965 1010);
PAINT MONO (-965 1010);
DISPLAY INVISIBLE (-965 1010);
FORCEPROP 1 LASTPIN (-975 1000) BN 5
J 0
(-987 1008);
DISPLAY 0.680851 (-987 1008);
PAINT GREEN (-987 1008);
FORCEPROP 2 LAST CDS_LIB standard
J 0
(-925 1000);
PAINT MONO (-925 1000);
DISPLAY INVISIBLE (-925 1000);
FORCEPROP 1 LAST BODY_TYPE PLUMBING
J 0
(-925 1050);
DISPLAY 0.872340 (-925 1050);
PAINT GREEN (-925 1050);
DISPLAY INVISIBLE (-925 1050);
FORCEPROP 1 LAST HDL_TAP TRUE
J 0
(-600 875);
DISPLAY 0.872340 (-600 875);
DISPLAY INVISIBLE (-600 875);
FORCEPROP 1 LAST PATH I53
J 0
(-927 1000);
DISPLAY 0.872340 (-927 1000);
PAINT GREEN (-927 1000);
DISPLAY INVISIBLE (-927 1000);
FORCEADD TAP..1
(-925 1100);
FORCEPROP 3 LASTPIN (-975 1100) SIG_NAME M_G_CPU1_SB_DQ<7>
J 0
(-965 1110);
DISPLAY 0.659574 (-965 1110);
PAINT MONO (-965 1110);
DISPLAY INVISIBLE (-965 1110);
FORCEPROP 1 LASTPIN (-975 1100) BN 7
J 0
(-987 1108);
DISPLAY 0.680851 (-987 1108);
PAINT GREEN (-987 1108);
FORCEPROP 2 LAST CDS_LIB standard
J 0
(-925 1100);
PAINT MONO (-925 1100);
DISPLAY INVISIBLE (-925 1100);
FORCEPROP 1 LAST BODY_TYPE PLUMBING
J 0
(-925 1150);
DISPLAY 0.872340 (-925 1150);
PAINT GREEN (-925 1150);
DISPLAY INVISIBLE (-925 1150);
FORCEPROP 1 LAST HDL_TAP TRUE
J 0
(-600 975);
DISPLAY 0.872340 (-600 975);
DISPLAY INVISIBLE (-600 975);
FORCEPROP 1 LAST PATH I54
J 0
(-927 1100);
DISPLAY 0.872340 (-927 1100);
PAINT GREEN (-927 1100);
DISPLAY INVISIBLE (-927 1100);
FORCEADD TAP..1
(-925 1050);
FORCEPROP 3 LASTPIN (-975 1050) SIG_NAME M_G_CPU1_SB_DQ<6>
J 0
(-965 1060);
DISPLAY 0.659574 (-965 1060);
PAINT MONO (-965 1060);
DISPLAY INVISIBLE (-965 1060);
FORCEPROP 1 LASTPIN (-975 1050) BN 6
J 0
(-987 1058);
DISPLAY 0.680851 (-987 1058);
PAINT GREEN (-987 1058);
FORCEPROP 2 LAST CDS_LIB standard
J 0
(-925 1050);
PAINT MONO (-925 1050);
DISPLAY INVISIBLE (-925 1050);
FORCEPROP 1 LAST BODY_TYPE PLUMBING
J 0
(-925 1100);
DISPLAY 0.872340 (-925 1100);
PAINT GREEN (-925 1100);
DISPLAY INVISIBLE (-925 1100);
FORCEPROP 1 LAST HDL_TAP TRUE
J 0
(-600 925);
DISPLAY 0.872340 (-600 925);
DISPLAY INVISIBLE (-600 925);
FORCEPROP 1 LAST PATH I55
J 0
(-927 1050);
DISPLAY 0.872340 (-927 1050);
PAINT GREEN (-927 1050);
DISPLAY INVISIBLE (-927 1050);
FORCEADD TAP..1
(-925 1150);
FORCEPROP 3 LASTPIN (-975 1150) SIG_NAME M_G_CPU1_SB_DQ<8>
J 0
(-965 1160);
DISPLAY 0.659574 (-965 1160);
PAINT MONO (-965 1160);
DISPLAY INVISIBLE (-965 1160);
FORCEPROP 1 LASTPIN (-975 1150) BN 8
J 0
(-987 1158);
DISPLAY 0.680851 (-987 1158);
PAINT GREEN (-987 1158);
FORCEPROP 2 LAST CDS_LIB standard
J 0
(-925 1150);
PAINT MONO (-925 1150);
DISPLAY INVISIBLE (-925 1150);
FORCEPROP 1 LAST BODY_TYPE PLUMBING
J 0
(-925 1200);
DISPLAY 0.872340 (-925 1200);
PAINT GREEN (-925 1200);
DISPLAY INVISIBLE (-925 1200);
FORCEPROP 1 LAST HDL_TAP TRUE
J 0
(-600 1025);
DISPLAY 0.872340 (-600 1025);
DISPLAY INVISIBLE (-600 1025);
FORCEPROP 1 LAST PATH I56
J 0
(-927 1150);
DISPLAY 0.872340 (-927 1150);
PAINT GREEN (-927 1150);
DISPLAY INVISIBLE (-927 1150);
FORCEADD TAP..1
(-925 1200);
FORCEPROP 3 LASTPIN (-975 1200) SIG_NAME M_G_CPU1_SB_DQ<9>
J 0
(-965 1210);
DISPLAY 0.659574 (-965 1210);
PAINT MONO (-965 1210);
DISPLAY INVISIBLE (-965 1210);
FORCEPROP 1 LASTPIN (-975 1200) BN 9
J 0
(-987 1208);
DISPLAY 0.680851 (-987 1208);
PAINT GREEN (-987 1208);
FORCEPROP 2 LAST CDS_LIB standard
J 0
(-925 1200);
PAINT MONO (-925 1200);
DISPLAY INVISIBLE (-925 1200);
FORCEPROP 1 LAST BODY_TYPE PLUMBING
J 0
(-925 1250);
DISPLAY 0.872340 (-925 1250);
PAINT GREEN (-925 1250);
DISPLAY INVISIBLE (-925 1250);
FORCEPROP 1 LAST HDL_TAP TRUE
J 0
(-600 1075);
DISPLAY 0.872340 (-600 1075);
DISPLAY INVISIBLE (-600 1075);
FORCEPROP 1 LAST PATH I57
J 0
(-927 1200);
DISPLAY 0.872340 (-927 1200);
PAINT GREEN (-927 1200);
DISPLAY INVISIBLE (-927 1200);
FORCEADD TAP..1
(-925 1250);
FORCEPROP 3 LASTPIN (-975 1250) SIG_NAME M_G_CPU1_SB_DQ<10>
J 0
(-965 1260);
DISPLAY 0.659574 (-965 1260);
PAINT MONO (-965 1260);
DISPLAY INVISIBLE (-965 1260);
FORCEPROP 1 LASTPIN (-975 1250) BN 10
J 0
(-987 1258);
DISPLAY 0.680851 (-987 1258);
PAINT GREEN (-987 1258);
FORCEPROP 2 LAST CDS_LIB standard
J 0
(-925 1250);
PAINT MONO (-925 1250);
DISPLAY INVISIBLE (-925 1250);
FORCEPROP 1 LAST BODY_TYPE PLUMBING
J 0
(-925 1300);
DISPLAY 0.872340 (-925 1300);
PAINT GREEN (-925 1300);
DISPLAY INVISIBLE (-925 1300);
FORCEPROP 1 LAST HDL_TAP TRUE
J 0
(-600 1125);
DISPLAY 0.872340 (-600 1125);
DISPLAY INVISIBLE (-600 1125);
FORCEPROP 1 LAST PATH I58
J 0
(-927 1250);
DISPLAY 0.872340 (-927 1250);
PAINT GREEN (-927 1250);
DISPLAY INVISIBLE (-927 1250);
FORCEADD TAP..1
(-925 1300);
FORCEPROP 3 LASTPIN (-975 1300) SIG_NAME M_G_CPU1_SB_DQ<11>
J 0
(-965 1310);
DISPLAY 0.659574 (-965 1310);
PAINT MONO (-965 1310);
DISPLAY INVISIBLE (-965 1310);
FORCEPROP 1 LASTPIN (-975 1300) BN 11
J 0
(-987 1308);
DISPLAY 0.680851 (-987 1308);
PAINT GREEN (-987 1308);
FORCEPROP 2 LAST CDS_LIB standard
J 0
(-925 1300);
PAINT MONO (-925 1300);
DISPLAY INVISIBLE (-925 1300);
FORCEPROP 1 LAST BODY_TYPE PLUMBING
J 0
(-925 1350);
DISPLAY 0.872340 (-925 1350);
PAINT GREEN (-925 1350);
DISPLAY INVISIBLE (-925 1350);
FORCEPROP 1 LAST HDL_TAP TRUE
J 0
(-600 1175);
DISPLAY 0.872340 (-600 1175);
DISPLAY INVISIBLE (-600 1175);
FORCEPROP 1 LAST PATH I59
J 0
(-927 1300);
DISPLAY 0.872340 (-927 1300);
PAINT GREEN (-927 1300);
DISPLAY INVISIBLE (-927 1300);
FORCEADD TAP..1
(-925 1350);
FORCEPROP 3 LASTPIN (-975 1350) SIG_NAME M_G_CPU1_SB_DQ<12>
J 0
(-965 1360);
DISPLAY 0.659574 (-965 1360);
PAINT MONO (-965 1360);
DISPLAY INVISIBLE (-965 1360);
FORCEPROP 1 LASTPIN (-975 1350) BN 12
J 0
(-987 1358);
DISPLAY 0.680851 (-987 1358);
PAINT GREEN (-987 1358);
FORCEPROP 2 LAST CDS_LIB standard
J 0
(-925 1350);
PAINT MONO (-925 1350);
DISPLAY INVISIBLE (-925 1350);
FORCEPROP 1 LAST BODY_TYPE PLUMBING
J 0
(-925 1400);
DISPLAY 0.872340 (-925 1400);
PAINT GREEN (-925 1400);
DISPLAY INVISIBLE (-925 1400);
FORCEPROP 1 LAST HDL_TAP TRUE
J 0
(-600 1225);
DISPLAY 0.872340 (-600 1225);
DISPLAY INVISIBLE (-600 1225);
FORCEPROP 1 LAST PATH I60
J 0
(-927 1350);
DISPLAY 0.872340 (-927 1350);
PAINT GREEN (-927 1350);
DISPLAY INVISIBLE (-927 1350);
FORCEADD TAP..1
(-925 1400);
FORCEPROP 3 LASTPIN (-975 1400) SIG_NAME M_G_CPU1_SB_DQ<13>
J 0
(-965 1410);
DISPLAY 0.659574 (-965 1410);
PAINT MONO (-965 1410);
DISPLAY INVISIBLE (-965 1410);
FORCEPROP 1 LASTPIN (-975 1400) BN 13
J 0
(-987 1408);
DISPLAY 0.680851 (-987 1408);
PAINT GREEN (-987 1408);
FORCEPROP 2 LAST CDS_LIB standard
J 0
(-925 1400);
PAINT MONO (-925 1400);
DISPLAY INVISIBLE (-925 1400);
FORCEPROP 1 LAST BODY_TYPE PLUMBING
J 0
(-925 1450);
DISPLAY 0.872340 (-925 1450);
PAINT GREEN (-925 1450);
DISPLAY INVISIBLE (-925 1450);
FORCEPROP 1 LAST HDL_TAP TRUE
J 0
(-600 1275);
DISPLAY 0.872340 (-600 1275);
DISPLAY INVISIBLE (-600 1275);
FORCEPROP 1 LAST PATH I61
J 0
(-927 1400);
DISPLAY 0.872340 (-927 1400);
PAINT GREEN (-927 1400);
DISPLAY INVISIBLE (-927 1400);
FORCEADD TAP..1
(-925 1450);
FORCEPROP 3 LASTPIN (-975 1450) SIG_NAME M_G_CPU1_SB_DQ<14>
J 0
(-965 1460);
DISPLAY 0.659574 (-965 1460);
PAINT MONO (-965 1460);
DISPLAY INVISIBLE (-965 1460);
FORCEPROP 1 LASTPIN (-975 1450) BN 14
J 0
(-987 1458);
DISPLAY 0.680851 (-987 1458);
PAINT GREEN (-987 1458);
FORCEPROP 2 LAST CDS_LIB standard
J 0
(-925 1450);
PAINT MONO (-925 1450);
DISPLAY INVISIBLE (-925 1450);
FORCEPROP 1 LAST BODY_TYPE PLUMBING
J 0
(-925 1500);
DISPLAY 0.872340 (-925 1500);
PAINT GREEN (-925 1500);
DISPLAY INVISIBLE (-925 1500);
FORCEPROP 1 LAST HDL_TAP TRUE
J 0
(-600 1325);
DISPLAY 0.872340 (-600 1325);
DISPLAY INVISIBLE (-600 1325);
FORCEPROP 1 LAST PATH I62
J 0
(-927 1450);
DISPLAY 0.872340 (-927 1450);
PAINT GREEN (-927 1450);
DISPLAY INVISIBLE (-927 1450);
FORCEADD TAP..1
(-925 1500);
FORCEPROP 3 LASTPIN (-975 1500) SIG_NAME M_G_CPU1_SB_DQ<15>
J 0
(-965 1510);
DISPLAY 0.659574 (-965 1510);
PAINT MONO (-965 1510);
DISPLAY INVISIBLE (-965 1510);
FORCEPROP 1 LASTPIN (-975 1500) BN 15
J 0
(-987 1508);
DISPLAY 0.680851 (-987 1508);
PAINT GREEN (-987 1508);
FORCEPROP 2 LAST CDS_LIB standard
J 0
(-925 1500);
PAINT MONO (-925 1500);
DISPLAY INVISIBLE (-925 1500);
FORCEPROP 1 LAST BODY_TYPE PLUMBING
J 0
(-925 1550);
DISPLAY 0.872340 (-925 1550);
PAINT GREEN (-925 1550);
DISPLAY INVISIBLE (-925 1550);
FORCEPROP 1 LAST HDL_TAP TRUE
J 0
(-600 1375);
DISPLAY 0.872340 (-600 1375);
DISPLAY INVISIBLE (-600 1375);
FORCEPROP 1 LAST PATH I63
J 0
(-927 1500);
DISPLAY 0.872340 (-927 1500);
PAINT GREEN (-927 1500);
DISPLAY INVISIBLE (-927 1500);
FORCEADD TAP..1
(-925 1550);
FORCEPROP 3 LASTPIN (-975 1550) SIG_NAME M_G_CPU1_SB_DQ<16>
J 0
(-965 1560);
DISPLAY 0.659574 (-965 1560);
PAINT MONO (-965 1560);
DISPLAY INVISIBLE (-965 1560);
FORCEPROP 1 LASTPIN (-975 1550) BN 16
J 0
(-987 1558);
DISPLAY 0.680851 (-987 1558);
PAINT GREEN (-987 1558);
FORCEPROP 2 LAST CDS_LIB standard
J 0
(-925 1550);
PAINT MONO (-925 1550);
DISPLAY INVISIBLE (-925 1550);
FORCEPROP 1 LAST BODY_TYPE PLUMBING
J 0
(-925 1600);
DISPLAY 0.872340 (-925 1600);
PAINT GREEN (-925 1600);
DISPLAY INVISIBLE (-925 1600);
FORCEPROP 1 LAST HDL_TAP TRUE
J 0
(-600 1425);
DISPLAY 0.872340 (-600 1425);
DISPLAY INVISIBLE (-600 1425);
FORCEPROP 1 LAST PATH I64
J 0
(-927 1550);
DISPLAY 0.872340 (-927 1550);
PAINT GREEN (-927 1550);
DISPLAY INVISIBLE (-927 1550);
FORCEADD TAP..1
(-925 1600);
FORCEPROP 3 LASTPIN (-975 1600) SIG_NAME M_G_CPU1_SB_DQ<17>
J 0
(-965 1610);
DISPLAY 0.659574 (-965 1610);
PAINT MONO (-965 1610);
DISPLAY INVISIBLE (-965 1610);
FORCEPROP 1 LASTPIN (-975 1600) BN 17
J 0
(-987 1608);
DISPLAY 0.680851 (-987 1608);
PAINT GREEN (-987 1608);
FORCEPROP 2 LAST CDS_LIB standard
J 0
(-925 1600);
PAINT MONO (-925 1600);
DISPLAY INVISIBLE (-925 1600);
FORCEPROP 1 LAST BODY_TYPE PLUMBING
J 0
(-925 1650);
DISPLAY 0.872340 (-925 1650);
PAINT GREEN (-925 1650);
DISPLAY INVISIBLE (-925 1650);
FORCEPROP 1 LAST HDL_TAP TRUE
J 0
(-600 1475);
DISPLAY 0.872340 (-600 1475);
DISPLAY INVISIBLE (-600 1475);
FORCEPROP 1 LAST PATH I65
J 0
(-927 1600);
DISPLAY 0.872340 (-927 1600);
PAINT GREEN (-927 1600);
DISPLAY INVISIBLE (-927 1600);
FORCEADD TAP..1
(-925 1650);
FORCEPROP 3 LASTPIN (-975 1650) SIG_NAME M_G_CPU1_SB_DQ<18>
J 0
(-965 1660);
DISPLAY 0.659574 (-965 1660);
PAINT MONO (-965 1660);
DISPLAY INVISIBLE (-965 1660);
FORCEPROP 1 LASTPIN (-975 1650) BN 18
J 0
(-987 1658);
DISPLAY 0.680851 (-987 1658);
PAINT GREEN (-987 1658);
FORCEPROP 2 LAST CDS_LIB standard
J 0
(-925 1650);
PAINT MONO (-925 1650);
DISPLAY INVISIBLE (-925 1650);
FORCEPROP 1 LAST BODY_TYPE PLUMBING
J 0
(-925 1700);
DISPLAY 0.872340 (-925 1700);
PAINT GREEN (-925 1700);
DISPLAY INVISIBLE (-925 1700);
FORCEPROP 1 LAST HDL_TAP TRUE
J 0
(-600 1525);
DISPLAY 0.872340 (-600 1525);
DISPLAY INVISIBLE (-600 1525);
FORCEPROP 1 LAST PATH I66
J 0
(-927 1650);
DISPLAY 0.872340 (-927 1650);
PAINT GREEN (-927 1650);
DISPLAY INVISIBLE (-927 1650);
FORCEADD TAP..1
(-925 1700);
FORCEPROP 3 LASTPIN (-975 1700) SIG_NAME M_G_CPU1_SB_DQ<19>
J 0
(-965 1710);
DISPLAY 0.659574 (-965 1710);
PAINT MONO (-965 1710);
DISPLAY INVISIBLE (-965 1710);
FORCEPROP 1 LASTPIN (-975 1700) BN 19
J 0
(-987 1708);
DISPLAY 0.680851 (-987 1708);
PAINT GREEN (-987 1708);
FORCEPROP 2 LAST CDS_LIB standard
J 0
(-925 1700);
PAINT MONO (-925 1700);
DISPLAY INVISIBLE (-925 1700);
FORCEPROP 1 LAST BODY_TYPE PLUMBING
J 0
(-925 1750);
DISPLAY 0.872340 (-925 1750);
PAINT GREEN (-925 1750);
DISPLAY INVISIBLE (-925 1750);
FORCEPROP 1 LAST HDL_TAP TRUE
J 0
(-600 1575);
DISPLAY 0.872340 (-600 1575);
DISPLAY INVISIBLE (-600 1575);
FORCEPROP 1 LAST PATH I67
J 0
(-927 1700);
DISPLAY 0.872340 (-927 1700);
PAINT GREEN (-927 1700);
DISPLAY INVISIBLE (-927 1700);
FORCEADD TAP..1
(-925 1750);
FORCEPROP 3 LASTPIN (-975 1750) SIG_NAME M_G_CPU1_SB_DQ<20>
J 0
(-965 1760);
DISPLAY 0.659574 (-965 1760);
PAINT MONO (-965 1760);
DISPLAY INVISIBLE (-965 1760);
FORCEPROP 1 LASTPIN (-975 1750) BN 20
J 0
(-987 1758);
DISPLAY 0.680851 (-987 1758);
PAINT GREEN (-987 1758);
FORCEPROP 2 LAST CDS_LIB standard
J 0
(-925 1750);
PAINT MONO (-925 1750);
DISPLAY INVISIBLE (-925 1750);
FORCEPROP 1 LAST BODY_TYPE PLUMBING
J 0
(-925 1800);
DISPLAY 0.872340 (-925 1800);
PAINT GREEN (-925 1800);
DISPLAY INVISIBLE (-925 1800);
FORCEPROP 1 LAST HDL_TAP TRUE
J 0
(-600 1625);
DISPLAY 0.872340 (-600 1625);
DISPLAY INVISIBLE (-600 1625);
FORCEPROP 1 LAST PATH I68
J 0
(-927 1750);
DISPLAY 0.872340 (-927 1750);
PAINT GREEN (-927 1750);
DISPLAY INVISIBLE (-927 1750);
FORCEADD TAP..1
(-925 1800);
FORCEPROP 3 LASTPIN (-975 1800) SIG_NAME M_G_CPU1_SB_DQ<21>
J 0
(-965 1810);
DISPLAY 0.659574 (-965 1810);
PAINT MONO (-965 1810);
DISPLAY INVISIBLE (-965 1810);
FORCEPROP 1 LASTPIN (-975 1800) BN 21
J 0
(-987 1808);
DISPLAY 0.680851 (-987 1808);
PAINT GREEN (-987 1808);
FORCEPROP 2 LAST CDS_LIB standard
J 0
(-925 1800);
PAINT MONO (-925 1800);
DISPLAY INVISIBLE (-925 1800);
FORCEPROP 1 LAST BODY_TYPE PLUMBING
J 0
(-925 1850);
DISPLAY 0.872340 (-925 1850);
PAINT GREEN (-925 1850);
DISPLAY INVISIBLE (-925 1850);
FORCEPROP 1 LAST HDL_TAP TRUE
J 0
(-600 1675);
DISPLAY 0.872340 (-600 1675);
DISPLAY INVISIBLE (-600 1675);
FORCEPROP 1 LAST PATH I69
J 0
(-927 1800);
DISPLAY 0.872340 (-927 1800);
PAINT GREEN (-927 1800);
DISPLAY INVISIBLE (-927 1800);
FORCEADD OFFPAGE..1
(-3450 1400);
FORCEPROP 2 LAST $XR7 113 
J 0
(-3942 1436);
DISPLAY 0.638298 (-3942 1436);
PAINT MONO (-3942 1436);
FORCEPROP 2 LAST $XR6 112 
J 0
(-3822 1436);
DISPLAY 0.638298 (-3822 1436);
PAINT MONO (-3822 1436);
FORCEPROP 2 LAST $XR5 111 
J 0
(-3942 1364);
DISPLAY 0.638298 (-3942 1364);
PAINT MONO (-3942 1364);
FORCEPROP 2 LAST $XR4 109 
J 0
(-3822 1364);
DISPLAY 0.638298 (-3822 1364);
PAINT MONO (-3822 1364);
FORCEPROP 2 LAST $XR3 108 
J 0
(-3702 1364);
DISPLAY 0.638298 (-3702 1364);
PAINT MONO (-3702 1364);
FORCEPROP 2 LAST $XR2 107 
J 0
(-3942 1400);
DISPLAY 0.638298 (-3942 1400);
PAINT MONO (-3942 1400);
FORCEPROP 2 LAST $XR1 106 
J 0
(-3822 1400);
DISPLAY 0.638298 (-3822 1400);
PAINT MONO (-3822 1400);
FORCEPROP 2 LAST $XR0 230 
J 0
(-3702 1400);
DISPLAY 0.638298 (-3702 1400);
PAINT MONO (-3702 1400);
FORCEPROP 2 LAST CDS_LIB standard
J 0
(-3450 1400);
PAINT MONO (-3450 1400);
DISPLAY INVISIBLE (-3450 1400);
FORCEPROP 1 LAST OFFPAGE TRUE
J 0
(-3125 1275);
DISPLAY 0.872340 (-3125 1275);
DISPLAY INVISIBLE (-3125 1275);
FORCEPROP 1 LAST COMMENT_BODY TRUE
J 0
(-3325 1300);
DISPLAY 0.872340 (-3325 1300);
PAINT GREEN (-3325 1300);
DISPLAY INVISIBLE (-3325 1300);
FORCEPROP 2 LAST PATH I7
J 0
(-3400 1475);
DISPLAY 1.021277 (-3400 1475);
DISPLAY INVISIBLE (-3400 1475);
FORCEADD TAP..1
(-925 1900);
FORCEPROP 3 LASTPIN (-975 1900) SIG_NAME M_G_CPU1_SB_DQ<23>
J 0
(-965 1910);
DISPLAY 0.659574 (-965 1910);
PAINT MONO (-965 1910);
DISPLAY INVISIBLE (-965 1910);
FORCEPROP 1 LASTPIN (-975 1900) BN 23
J 0
(-987 1908);
DISPLAY 0.680851 (-987 1908);
PAINT GREEN (-987 1908);
FORCEPROP 2 LAST CDS_LIB standard
J 0
(-925 1900);
DISPLAY INVISIBLE (-925 1900);
FORCEPROP 1 LAST BODY_TYPE PLUMBING
J 0
(-925 1950);
DISPLAY 0.872340 (-925 1950);
PAINT GREEN (-925 1950);
DISPLAY INVISIBLE (-925 1950);
FORCEPROP 1 LAST HDL_TAP TRUE
J 0
(-600 1775);
DISPLAY 0.872340 (-600 1775);
DISPLAY INVISIBLE (-600 1775);
FORCEPROP 1 LAST PATH I70
J 0
(-927 1900);
DISPLAY 0.872340 (-927 1900);
PAINT GREEN (-927 1900);
DISPLAY INVISIBLE (-927 1900);
FORCEADD TAP..1
(-925 1850);
FORCEPROP 3 LASTPIN (-975 1850) SIG_NAME M_G_CPU1_SB_DQ<22>
J 0
(-965 1860);
DISPLAY 0.659574 (-965 1860);
PAINT MONO (-965 1860);
DISPLAY INVISIBLE (-965 1860);
FORCEPROP 1 LASTPIN (-975 1850) BN 22
J 0
(-987 1858);
DISPLAY 0.680851 (-987 1858);
PAINT GREEN (-987 1858);
FORCEPROP 2 LAST CDS_LIB standard
J 0
(-925 1850);
DISPLAY INVISIBLE (-925 1850);
FORCEPROP 1 LAST BODY_TYPE PLUMBING
J 0
(-925 1900);
DISPLAY 0.872340 (-925 1900);
PAINT GREEN (-925 1900);
DISPLAY INVISIBLE (-925 1900);
FORCEPROP 1 LAST HDL_TAP TRUE
J 0
(-600 1725);
DISPLAY 0.872340 (-600 1725);
DISPLAY INVISIBLE (-600 1725);
FORCEPROP 1 LAST PATH I71
J 0
(-927 1850);
DISPLAY 0.872340 (-927 1850);
PAINT GREEN (-927 1850);
DISPLAY INVISIBLE (-927 1850);
FORCEADD TAP..1
(-925 1950);
FORCEPROP 3 LASTPIN (-975 1950) SIG_NAME M_G_CPU1_SB_DQ<24>
J 0
(-965 1960);
DISPLAY 0.659574 (-965 1960);
PAINT MONO (-965 1960);
DISPLAY INVISIBLE (-965 1960);
FORCEPROP 1 LASTPIN (-975 1950) BN 24
J 0
(-987 1958);
DISPLAY 0.680851 (-987 1958);
PAINT GREEN (-987 1958);
FORCEPROP 2 LAST CDS_LIB standard
J 0
(-925 1950);
DISPLAY INVISIBLE (-925 1950);
FORCEPROP 1 LAST BODY_TYPE PLUMBING
J 0
(-925 2000);
DISPLAY 0.872340 (-925 2000);
PAINT GREEN (-925 2000);
DISPLAY INVISIBLE (-925 2000);
FORCEPROP 1 LAST HDL_TAP TRUE
J 0
(-600 1825);
DISPLAY 0.872340 (-600 1825);
DISPLAY INVISIBLE (-600 1825);
FORCEPROP 1 LAST PATH I72
J 0
(-927 1950);
DISPLAY 0.872340 (-927 1950);
PAINT GREEN (-927 1950);
DISPLAY INVISIBLE (-927 1950);
FORCEADD TAP..1
(-925 2000);
FORCEPROP 3 LASTPIN (-975 2000) SIG_NAME M_G_CPU1_SB_DQ<25>
J 0
(-965 2010);
DISPLAY 0.659574 (-965 2010);
PAINT MONO (-965 2010);
DISPLAY INVISIBLE (-965 2010);
FORCEPROP 1 LASTPIN (-975 2000) BN 25
J 0
(-987 2008);
DISPLAY 0.680851 (-987 2008);
PAINT GREEN (-987 2008);
FORCEPROP 2 LAST CDS_LIB standard
J 0
(-925 2000);
DISPLAY INVISIBLE (-925 2000);
FORCEPROP 1 LAST BODY_TYPE PLUMBING
J 0
(-925 2050);
DISPLAY 0.872340 (-925 2050);
PAINT GREEN (-925 2050);
DISPLAY INVISIBLE (-925 2050);
FORCEPROP 1 LAST HDL_TAP TRUE
J 0
(-600 1875);
DISPLAY 0.872340 (-600 1875);
DISPLAY INVISIBLE (-600 1875);
FORCEPROP 1 LAST PATH I73
J 0
(-927 2000);
DISPLAY 0.872340 (-927 2000);
PAINT GREEN (-927 2000);
DISPLAY INVISIBLE (-927 2000);
FORCEADD TAP..1
(-925 2050);
FORCEPROP 3 LASTPIN (-975 2050) SIG_NAME M_G_CPU1_SB_DQ<26>
J 0
(-965 2060);
DISPLAY 0.659574 (-965 2060);
PAINT MONO (-965 2060);
DISPLAY INVISIBLE (-965 2060);
FORCEPROP 1 LASTPIN (-975 2050) BN 26
J 0
(-987 2058);
DISPLAY 0.680851 (-987 2058);
PAINT GREEN (-987 2058);
FORCEPROP 2 LAST CDS_LIB standard
J 0
(-925 2050);
DISPLAY INVISIBLE (-925 2050);
FORCEPROP 1 LAST BODY_TYPE PLUMBING
J 0
(-925 2100);
DISPLAY 0.872340 (-925 2100);
PAINT GREEN (-925 2100);
DISPLAY INVISIBLE (-925 2100);
FORCEPROP 1 LAST HDL_TAP TRUE
J 0
(-600 1925);
DISPLAY 0.872340 (-600 1925);
DISPLAY INVISIBLE (-600 1925);
FORCEPROP 1 LAST PATH I74
J 0
(-927 2050);
DISPLAY 0.872340 (-927 2050);
PAINT GREEN (-927 2050);
DISPLAY INVISIBLE (-927 2050);
FORCEADD TAP..1
(-925 2150);
FORCEPROP 3 LASTPIN (-975 2150) SIG_NAME M_G_CPU1_SB_DQ<28>
J 0
(-965 2160);
DISPLAY 0.659574 (-965 2160);
PAINT MONO (-965 2160);
DISPLAY INVISIBLE (-965 2160);
FORCEPROP 1 LASTPIN (-975 2150) BN 28
J 0
(-987 2158);
DISPLAY 0.680851 (-987 2158);
PAINT GREEN (-987 2158);
FORCEPROP 2 LAST CDS_LIB standard
J 0
(-925 2150);
DISPLAY INVISIBLE (-925 2150);
FORCEPROP 1 LAST BODY_TYPE PLUMBING
J 0
(-925 2200);
DISPLAY 0.872340 (-925 2200);
PAINT GREEN (-925 2200);
DISPLAY INVISIBLE (-925 2200);
FORCEPROP 1 LAST HDL_TAP TRUE
J 0
(-600 2025);
DISPLAY 0.872340 (-600 2025);
DISPLAY INVISIBLE (-600 2025);
FORCEPROP 1 LAST PATH I75
J 0
(-927 2150);
DISPLAY 0.872340 (-927 2150);
PAINT GREEN (-927 2150);
DISPLAY INVISIBLE (-927 2150);
FORCEADD TAP..1
(-925 2100);
FORCEPROP 3 LASTPIN (-975 2100) SIG_NAME M_G_CPU1_SB_DQ<27>
J 0
(-965 2110);
DISPLAY 0.659574 (-965 2110);
PAINT MONO (-965 2110);
DISPLAY INVISIBLE (-965 2110);
FORCEPROP 1 LASTPIN (-975 2100) BN 27
J 0
(-987 2108);
DISPLAY 0.680851 (-987 2108);
PAINT GREEN (-987 2108);
FORCEPROP 2 LAST CDS_LIB standard
J 0
(-925 2100);
DISPLAY INVISIBLE (-925 2100);
FORCEPROP 1 LAST BODY_TYPE PLUMBING
J 0
(-925 2150);
DISPLAY 0.872340 (-925 2150);
PAINT GREEN (-925 2150);
DISPLAY INVISIBLE (-925 2150);
FORCEPROP 1 LAST HDL_TAP TRUE
J 0
(-600 1975);
DISPLAY 0.872340 (-600 1975);
DISPLAY INVISIBLE (-600 1975);
FORCEPROP 1 LAST PATH I76
J 0
(-927 2100);
DISPLAY 0.872340 (-927 2100);
PAINT GREEN (-927 2100);
DISPLAY INVISIBLE (-927 2100);
FORCEADD TAP..1
(-925 2200);
FORCEPROP 3 LASTPIN (-975 2200) SIG_NAME M_G_CPU1_SB_DQ<29>
J 0
(-965 2210);
DISPLAY 0.659574 (-965 2210);
PAINT MONO (-965 2210);
DISPLAY INVISIBLE (-965 2210);
FORCEPROP 1 LASTPIN (-975 2200) BN 29
J 0
(-987 2208);
DISPLAY 0.680851 (-987 2208);
PAINT GREEN (-987 2208);
FORCEPROP 2 LAST CDS_LIB standard
J 0
(-925 2200);
DISPLAY INVISIBLE (-925 2200);
FORCEPROP 1 LAST BODY_TYPE PLUMBING
J 0
(-925 2250);
DISPLAY 0.872340 (-925 2250);
PAINT GREEN (-925 2250);
DISPLAY INVISIBLE (-925 2250);
FORCEPROP 1 LAST HDL_TAP TRUE
J 0
(-600 2075);
DISPLAY 0.872340 (-600 2075);
DISPLAY INVISIBLE (-600 2075);
FORCEPROP 1 LAST PATH I77
J 0
(-927 2200);
DISPLAY 0.872340 (-927 2200);
PAINT GREEN (-927 2200);
DISPLAY INVISIBLE (-927 2200);
FORCEADD TAP..1
(-925 2250);
FORCEPROP 3 LASTPIN (-975 2250) SIG_NAME M_G_CPU1_SB_DQ<30>
J 0
(-965 2260);
DISPLAY 0.659574 (-965 2260);
PAINT MONO (-965 2260);
DISPLAY INVISIBLE (-965 2260);
FORCEPROP 1 LASTPIN (-975 2250) BN 30
J 0
(-987 2258);
DISPLAY 0.680851 (-987 2258);
PAINT GREEN (-987 2258);
FORCEPROP 2 LAST CDS_LIB standard
J 0
(-925 2250);
DISPLAY INVISIBLE (-925 2250);
FORCEPROP 1 LAST BODY_TYPE PLUMBING
J 0
(-925 2300);
DISPLAY 0.872340 (-925 2300);
PAINT GREEN (-925 2300);
DISPLAY INVISIBLE (-925 2300);
FORCEPROP 1 LAST HDL_TAP TRUE
J 0
(-600 2125);
DISPLAY 0.872340 (-600 2125);
DISPLAY INVISIBLE (-600 2125);
FORCEPROP 1 LAST PATH I78
J 0
(-927 2250);
DISPLAY 0.872340 (-927 2250);
PAINT GREEN (-927 2250);
DISPLAY INVISIBLE (-927 2250);
FORCEADD TAP..1
(-925 2400);
FORCEPROP 3 LASTPIN (-975 2400) SIG_NAME M_G_CPU1_SA_DQ<0>
J 0
(-965 2410);
DISPLAY 0.659574 (-965 2410);
PAINT MONO (-965 2410);
DISPLAY INVISIBLE (-965 2410);
FORCEPROP 1 LASTPIN (-975 2400) BN 0
J 0
(-987 2408);
DISPLAY 0.680851 (-987 2408);
PAINT GREEN (-987 2408);
FORCEPROP 2 LAST CDS_LIB standard
J 0
(-925 2400);
PAINT MONO (-925 2400);
DISPLAY INVISIBLE (-925 2400);
FORCEPROP 1 LAST BODY_TYPE PLUMBING
J 0
(-925 2450);
DISPLAY 0.872340 (-925 2450);
PAINT GREEN (-925 2450);
DISPLAY INVISIBLE (-925 2450);
FORCEPROP 1 LAST HDL_TAP TRUE
J 0
(-600 2275);
DISPLAY 0.872340 (-600 2275);
DISPLAY INVISIBLE (-600 2275);
FORCEPROP 1 LAST PATH I79
J 0
(-927 2400);
DISPLAY 0.872340 (-927 2400);
PAINT GREEN (-927 2400);
DISPLAY INVISIBLE (-927 2400);
FORCEADD OFFPAGE..1
(-3475 1600);
FORCEPROP 2 LAST $XR1 111 
J 0
(-3816 1600);
DISPLAY 0.638298 (-3816 1600);
PAINT MONO (-3816 1600);
FORCEPROP 2 LAST $XR0 57 
J 0
(-3696 1600);
DISPLAY 0.638298 (-3696 1600);
PAINT MONO (-3696 1600);
FORCEPROP 2 LAST CDS_LIB standard
J 0
(-3475 1600);
PAINT MONO (-3475 1600);
DISPLAY INVISIBLE (-3475 1600);
FORCEPROP 1 LAST OFFPAGE TRUE
J 0
(-3150 1475);
DISPLAY 0.872340 (-3150 1475);
DISPLAY INVISIBLE (-3150 1475);
FORCEPROP 1 LAST COMMENT_BODY TRUE
J 0
(-3350 1500);
DISPLAY 0.872340 (-3350 1500);
PAINT GREEN (-3350 1500);
DISPLAY INVISIBLE (-3350 1500);
FORCEPROP 2 LAST PATH I8
J 0
(-3425 1675);
DISPLAY 1.021277 (-3425 1675);
DISPLAY INVISIBLE (-3425 1675);
FORCEADD TAP..1
(-925 2300);
FORCEPROP 3 LASTPIN (-975 2300) SIG_NAME M_G_CPU1_SB_DQ<31>
J 0
(-965 2310);
DISPLAY 0.659574 (-965 2310);
PAINT MONO (-965 2310);
DISPLAY INVISIBLE (-965 2310);
FORCEPROP 1 LASTPIN (-975 2300) BN 31
J 0
(-987 2308);
DISPLAY 0.680851 (-987 2308);
PAINT GREEN (-987 2308);
FORCEPROP 2 LAST CDS_LIB standard
J 0
(-925 2300);
DISPLAY INVISIBLE (-925 2300);
FORCEPROP 1 LAST BODY_TYPE PLUMBING
J 0
(-925 2350);
DISPLAY 0.872340 (-925 2350);
PAINT GREEN (-925 2350);
DISPLAY INVISIBLE (-925 2350);
FORCEPROP 1 LAST HDL_TAP TRUE
J 0
(-600 2175);
DISPLAY 0.872340 (-600 2175);
DISPLAY INVISIBLE (-600 2175);
FORCEPROP 1 LAST PATH I80
J 0
(-927 2300);
DISPLAY 0.872340 (-927 2300);
PAINT GREEN (-927 2300);
DISPLAY INVISIBLE (-927 2300);
FORCEADD TAP..1
(-925 2500);
FORCEPROP 3 LASTPIN (-975 2500) SIG_NAME M_G_CPU1_SA_DQ<2>
J 0
(-965 2510);
DISPLAY 0.659574 (-965 2510);
PAINT MONO (-965 2510);
DISPLAY INVISIBLE (-965 2510);
FORCEPROP 1 LASTPIN (-975 2500) BN 2
J 0
(-987 2508);
DISPLAY 0.680851 (-987 2508);
PAINT GREEN (-987 2508);
FORCEPROP 2 LAST CDS_LIB standard
J 0
(-925 2500);
PAINT MONO (-925 2500);
DISPLAY INVISIBLE (-925 2500);
FORCEPROP 1 LAST BODY_TYPE PLUMBING
J 0
(-925 2550);
DISPLAY 0.872340 (-925 2550);
PAINT GREEN (-925 2550);
DISPLAY INVISIBLE (-925 2550);
FORCEPROP 1 LAST HDL_TAP TRUE
J 0
(-600 2375);
DISPLAY 0.872340 (-600 2375);
DISPLAY INVISIBLE (-600 2375);
FORCEPROP 1 LAST PATH I81
J 0
(-927 2500);
DISPLAY 0.872340 (-927 2500);
PAINT GREEN (-927 2500);
DISPLAY INVISIBLE (-927 2500);
FORCEADD TAP..1
(-925 2450);
FORCEPROP 3 LASTPIN (-975 2450) SIG_NAME M_G_CPU1_SA_DQ<1>
J 0
(-965 2460);
DISPLAY 0.659574 (-965 2460);
PAINT MONO (-965 2460);
DISPLAY INVISIBLE (-965 2460);
FORCEPROP 1 LASTPIN (-975 2450) BN 1
J 0
(-987 2458);
DISPLAY 0.680851 (-987 2458);
PAINT GREEN (-987 2458);
FORCEPROP 2 LAST CDS_LIB standard
J 0
(-925 2450);
PAINT MONO (-925 2450);
DISPLAY INVISIBLE (-925 2450);
FORCEPROP 1 LAST BODY_TYPE PLUMBING
J 0
(-925 2500);
DISPLAY 0.872340 (-925 2500);
PAINT GREEN (-925 2500);
DISPLAY INVISIBLE (-925 2500);
FORCEPROP 1 LAST HDL_TAP TRUE
J 0
(-600 2325);
DISPLAY 0.872340 (-600 2325);
DISPLAY INVISIBLE (-600 2325);
FORCEPROP 1 LAST PATH I82
J 0
(-927 2450);
DISPLAY 0.872340 (-927 2450);
PAINT GREEN (-927 2450);
DISPLAY INVISIBLE (-927 2450);
FORCEADD TAP..1
(-925 2600);
FORCEPROP 3 LASTPIN (-975 2600) SIG_NAME M_G_CPU1_SA_DQ<4>
J 0
(-965 2610);
DISPLAY 0.659574 (-965 2610);
PAINT MONO (-965 2610);
DISPLAY INVISIBLE (-965 2610);
FORCEPROP 1 LASTPIN (-975 2600) BN 4
J 0
(-987 2608);
DISPLAY 0.680851 (-987 2608);
PAINT GREEN (-987 2608);
FORCEPROP 2 LAST CDS_LIB standard
J 0
(-925 2600);
PAINT MONO (-925 2600);
DISPLAY INVISIBLE (-925 2600);
FORCEPROP 1 LAST BODY_TYPE PLUMBING
J 0
(-925 2650);
DISPLAY 0.872340 (-925 2650);
PAINT GREEN (-925 2650);
DISPLAY INVISIBLE (-925 2650);
FORCEPROP 1 LAST HDL_TAP TRUE
J 0
(-600 2475);
DISPLAY 0.872340 (-600 2475);
DISPLAY INVISIBLE (-600 2475);
FORCEPROP 1 LAST PATH I83
J 0
(-927 2600);
DISPLAY 0.872340 (-927 2600);
PAINT GREEN (-927 2600);
DISPLAY INVISIBLE (-927 2600);
FORCEADD TAP..1
(-925 2550);
FORCEPROP 3 LASTPIN (-975 2550) SIG_NAME M_G_CPU1_SA_DQ<3>
J 0
(-965 2560);
DISPLAY 0.659574 (-965 2560);
PAINT MONO (-965 2560);
DISPLAY INVISIBLE (-965 2560);
FORCEPROP 1 LASTPIN (-975 2550) BN 3
J 0
(-987 2558);
DISPLAY 0.680851 (-987 2558);
PAINT GREEN (-987 2558);
FORCEPROP 2 LAST CDS_LIB standard
J 0
(-925 2550);
PAINT MONO (-925 2550);
DISPLAY INVISIBLE (-925 2550);
FORCEPROP 1 LAST BODY_TYPE PLUMBING
J 0
(-925 2600);
DISPLAY 0.872340 (-925 2600);
PAINT GREEN (-925 2600);
DISPLAY INVISIBLE (-925 2600);
FORCEPROP 1 LAST HDL_TAP TRUE
J 0
(-600 2425);
DISPLAY 0.872340 (-600 2425);
DISPLAY INVISIBLE (-600 2425);
FORCEPROP 1 LAST PATH I84
J 0
(-927 2550);
DISPLAY 0.872340 (-927 2550);
PAINT GREEN (-927 2550);
DISPLAY INVISIBLE (-927 2550);
FORCEADD TAP..1
(-925 2650);
FORCEPROP 3 LASTPIN (-975 2650) SIG_NAME M_G_CPU1_SA_DQ<5>
J 0
(-965 2660);
DISPLAY 0.659574 (-965 2660);
PAINT MONO (-965 2660);
DISPLAY INVISIBLE (-965 2660);
FORCEPROP 1 LASTPIN (-975 2650) BN 5
J 0
(-987 2658);
DISPLAY 0.680851 (-987 2658);
PAINT GREEN (-987 2658);
FORCEPROP 2 LAST CDS_LIB standard
J 0
(-925 2650);
PAINT MONO (-925 2650);
DISPLAY INVISIBLE (-925 2650);
FORCEPROP 1 LAST BODY_TYPE PLUMBING
J 0
(-925 2700);
DISPLAY 0.872340 (-925 2700);
PAINT GREEN (-925 2700);
DISPLAY INVISIBLE (-925 2700);
FORCEPROP 1 LAST HDL_TAP TRUE
J 0
(-600 2525);
DISPLAY 0.872340 (-600 2525);
DISPLAY INVISIBLE (-600 2525);
FORCEPROP 1 LAST PATH I85
J 0
(-927 2650);
DISPLAY 0.872340 (-927 2650);
PAINT GREEN (-927 2650);
DISPLAY INVISIBLE (-927 2650);
FORCEADD TAP..1
(-925 2750);
FORCEPROP 3 LASTPIN (-975 2750) SIG_NAME M_G_CPU1_SA_DQ<7>
J 0
(-965 2760);
DISPLAY 0.659574 (-965 2760);
PAINT MONO (-965 2760);
DISPLAY INVISIBLE (-965 2760);
FORCEPROP 1 LASTPIN (-975 2750) BN 7
J 0
(-987 2758);
DISPLAY 0.680851 (-987 2758);
PAINT GREEN (-987 2758);
FORCEPROP 2 LAST CDS_LIB standard
J 0
(-925 2750);
PAINT MONO (-925 2750);
DISPLAY INVISIBLE (-925 2750);
FORCEPROP 1 LAST BODY_TYPE PLUMBING
J 0
(-925 2800);
DISPLAY 0.872340 (-925 2800);
PAINT GREEN (-925 2800);
DISPLAY INVISIBLE (-925 2800);
FORCEPROP 1 LAST HDL_TAP TRUE
J 0
(-600 2625);
DISPLAY 0.872340 (-600 2625);
DISPLAY INVISIBLE (-600 2625);
FORCEPROP 1 LAST PATH I86
J 0
(-927 2750);
DISPLAY 0.872340 (-927 2750);
PAINT GREEN (-927 2750);
DISPLAY INVISIBLE (-927 2750);
FORCEADD TAP..1
(-925 2700);
FORCEPROP 3 LASTPIN (-975 2700) SIG_NAME M_G_CPU1_SA_DQ<6>
J 0
(-965 2710);
DISPLAY 0.659574 (-965 2710);
PAINT MONO (-965 2710);
DISPLAY INVISIBLE (-965 2710);
FORCEPROP 1 LASTPIN (-975 2700) BN 6
J 0
(-987 2708);
DISPLAY 0.680851 (-987 2708);
PAINT GREEN (-987 2708);
FORCEPROP 2 LAST CDS_LIB standard
J 0
(-925 2700);
PAINT MONO (-925 2700);
DISPLAY INVISIBLE (-925 2700);
FORCEPROP 1 LAST BODY_TYPE PLUMBING
J 0
(-925 2750);
DISPLAY 0.872340 (-925 2750);
PAINT GREEN (-925 2750);
DISPLAY INVISIBLE (-925 2750);
FORCEPROP 1 LAST HDL_TAP TRUE
J 0
(-600 2575);
DISPLAY 0.872340 (-600 2575);
DISPLAY INVISIBLE (-600 2575);
FORCEPROP 1 LAST PATH I87
J 0
(-927 2700);
DISPLAY 0.872340 (-927 2700);
PAINT GREEN (-927 2700);
DISPLAY INVISIBLE (-927 2700);
FORCEADD TAP..1
(-925 2800);
FORCEPROP 3 LASTPIN (-975 2800) SIG_NAME M_G_CPU1_SA_DQ<8>
J 0
(-965 2810);
DISPLAY 0.659574 (-965 2810);
PAINT MONO (-965 2810);
DISPLAY INVISIBLE (-965 2810);
FORCEPROP 1 LASTPIN (-975 2800) BN 8
J 0
(-987 2808);
DISPLAY 0.680851 (-987 2808);
PAINT GREEN (-987 2808);
FORCEPROP 2 LAST CDS_LIB standard
J 0
(-925 2800);
PAINT MONO (-925 2800);
DISPLAY INVISIBLE (-925 2800);
FORCEPROP 1 LAST BODY_TYPE PLUMBING
J 0
(-925 2850);
DISPLAY 0.872340 (-925 2850);
PAINT GREEN (-925 2850);
DISPLAY INVISIBLE (-925 2850);
FORCEPROP 1 LAST HDL_TAP TRUE
J 0
(-600 2675);
DISPLAY 0.872340 (-600 2675);
DISPLAY INVISIBLE (-600 2675);
FORCEPROP 1 LAST PATH I88
J 0
(-927 2800);
DISPLAY 0.872340 (-927 2800);
PAINT GREEN (-927 2800);
DISPLAY INVISIBLE (-927 2800);
FORCEADD TAP..1
(-925 2900);
FORCEPROP 3 LASTPIN (-975 2900) SIG_NAME M_G_CPU1_SA_DQ<10>
J 0
(-965 2910);
DISPLAY 0.659574 (-965 2910);
PAINT MONO (-965 2910);
DISPLAY INVISIBLE (-965 2910);
FORCEPROP 1 LASTPIN (-975 2900) BN 10
J 0
(-987 2908);
DISPLAY 0.680851 (-987 2908);
PAINT GREEN (-987 2908);
FORCEPROP 2 LAST CDS_LIB standard
J 0
(-925 2900);
PAINT MONO (-925 2900);
DISPLAY INVISIBLE (-925 2900);
FORCEPROP 1 LAST BODY_TYPE PLUMBING
J 0
(-925 2950);
DISPLAY 0.872340 (-925 2950);
PAINT GREEN (-925 2950);
DISPLAY INVISIBLE (-925 2950);
FORCEPROP 1 LAST HDL_TAP TRUE
J 0
(-600 2775);
DISPLAY 0.872340 (-600 2775);
DISPLAY INVISIBLE (-600 2775);
FORCEPROP 1 LAST PATH I89
J 0
(-927 2900);
DISPLAY 0.872340 (-927 2900);
PAINT GREEN (-927 2900);
DISPLAY INVISIBLE (-927 2900);
FORCEADD OFFPAGE..1
(-3450 1450);
FORCEPROP 2 LAST $XR0 110 
J 0
(-3702 1450);
DISPLAY 0.638298 (-3702 1450);
PAINT MONO (-3702 1450);
FORCEPROP 2 LAST CDS_LIB standard
J 0
(-3450 1450);
PAINT MONO (-3450 1450);
DISPLAY INVISIBLE (-3450 1450);
FORCEPROP 1 LAST OFFPAGE TRUE
J 0
(-3125 1325);
DISPLAY 0.872340 (-3125 1325);
DISPLAY INVISIBLE (-3125 1325);
FORCEPROP 1 LAST COMMENT_BODY TRUE
J 0
(-3325 1350);
DISPLAY 0.872340 (-3325 1350);
PAINT GREEN (-3325 1350);
DISPLAY INVISIBLE (-3325 1350);
FORCEPROP 2 LAST PATH I9
J 0
(-3400 1525);
DISPLAY 1.021277 (-3400 1525);
DISPLAY INVISIBLE (-3400 1525);
FORCEADD TAP..1
(-925 2850);
FORCEPROP 3 LASTPIN (-975 2850) SIG_NAME M_G_CPU1_SA_DQ<9>
J 0
(-965 2860);
DISPLAY 0.659574 (-965 2860);
PAINT MONO (-965 2860);
DISPLAY INVISIBLE (-965 2860);
FORCEPROP 1 LASTPIN (-975 2850) BN 9
J 0
(-987 2858);
DISPLAY 0.680851 (-987 2858);
PAINT GREEN (-987 2858);
FORCEPROP 2 LAST CDS_LIB standard
J 0
(-925 2850);
PAINT MONO (-925 2850);
DISPLAY INVISIBLE (-925 2850);
FORCEPROP 1 LAST BODY_TYPE PLUMBING
J 0
(-925 2900);
DISPLAY 0.872340 (-925 2900);
PAINT GREEN (-925 2900);
DISPLAY INVISIBLE (-925 2900);
FORCEPROP 1 LAST HDL_TAP TRUE
J 0
(-600 2725);
DISPLAY 0.872340 (-600 2725);
DISPLAY INVISIBLE (-600 2725);
FORCEPROP 1 LAST PATH I90
J 0
(-927 2850);
DISPLAY 0.872340 (-927 2850);
PAINT GREEN (-927 2850);
DISPLAY INVISIBLE (-927 2850);
FORCEADD TAP..1
(-925 2950);
FORCEPROP 3 LASTPIN (-975 2950) SIG_NAME M_G_CPU1_SA_DQ<11>
J 0
(-965 2960);
DISPLAY 0.659574 (-965 2960);
PAINT MONO (-965 2960);
DISPLAY INVISIBLE (-965 2960);
FORCEPROP 1 LASTPIN (-975 2950) BN 11
J 0
(-987 2958);
DISPLAY 0.680851 (-987 2958);
PAINT GREEN (-987 2958);
FORCEPROP 2 LAST CDS_LIB standard
J 0
(-925 2950);
PAINT MONO (-925 2950);
DISPLAY INVISIBLE (-925 2950);
FORCEPROP 1 LAST BODY_TYPE PLUMBING
J 0
(-925 3000);
DISPLAY 0.872340 (-925 3000);
PAINT GREEN (-925 3000);
DISPLAY INVISIBLE (-925 3000);
FORCEPROP 1 LAST HDL_TAP TRUE
J 0
(-600 2825);
DISPLAY 0.872340 (-600 2825);
DISPLAY INVISIBLE (-600 2825);
FORCEPROP 1 LAST PATH I91
J 0
(-927 2950);
DISPLAY 0.872340 (-927 2950);
PAINT GREEN (-927 2950);
DISPLAY INVISIBLE (-927 2950);
FORCEADD TAP..1
(-925 3050);
FORCEPROP 3 LASTPIN (-975 3050) SIG_NAME M_G_CPU1_SA_DQ<13>
J 0
(-965 3060);
DISPLAY 0.659574 (-965 3060);
PAINT MONO (-965 3060);
DISPLAY INVISIBLE (-965 3060);
FORCEPROP 1 LASTPIN (-975 3050) BN 13
J 0
(-987 3058);
DISPLAY 0.680851 (-987 3058);
PAINT GREEN (-987 3058);
FORCEPROP 2 LAST CDS_LIB standard
J 0
(-925 3050);
PAINT MONO (-925 3050);
DISPLAY INVISIBLE (-925 3050);
FORCEPROP 1 LAST BODY_TYPE PLUMBING
J 0
(-925 3100);
DISPLAY 0.872340 (-925 3100);
PAINT GREEN (-925 3100);
DISPLAY INVISIBLE (-925 3100);
FORCEPROP 1 LAST HDL_TAP TRUE
J 0
(-600 2925);
DISPLAY 0.872340 (-600 2925);
DISPLAY INVISIBLE (-600 2925);
FORCEPROP 1 LAST PATH I92
J 0
(-927 3050);
DISPLAY 0.872340 (-927 3050);
PAINT GREEN (-927 3050);
DISPLAY INVISIBLE (-927 3050);
FORCEADD TAP..1
(-925 3000);
FORCEPROP 3 LASTPIN (-975 3000) SIG_NAME M_G_CPU1_SA_DQ<12>
J 0
(-965 3010);
DISPLAY 0.659574 (-965 3010);
PAINT MONO (-965 3010);
DISPLAY INVISIBLE (-965 3010);
FORCEPROP 1 LASTPIN (-975 3000) BN 12
J 0
(-987 3008);
DISPLAY 0.680851 (-987 3008);
PAINT GREEN (-987 3008);
FORCEPROP 2 LAST CDS_LIB standard
J 0
(-925 3000);
PAINT MONO (-925 3000);
DISPLAY INVISIBLE (-925 3000);
FORCEPROP 1 LAST BODY_TYPE PLUMBING
J 0
(-925 3050);
DISPLAY 0.872340 (-925 3050);
PAINT GREEN (-925 3050);
DISPLAY INVISIBLE (-925 3050);
FORCEPROP 1 LAST HDL_TAP TRUE
J 0
(-600 2875);
DISPLAY 0.872340 (-600 2875);
DISPLAY INVISIBLE (-600 2875);
FORCEPROP 1 LAST PATH I93
J 0
(-927 3000);
DISPLAY 0.872340 (-927 3000);
PAINT GREEN (-927 3000);
DISPLAY INVISIBLE (-927 3000);
FORCEADD TAP..1
(-925 3150);
FORCEPROP 3 LASTPIN (-975 3150) SIG_NAME M_G_CPU1_SA_DQ<15>
J 0
(-965 3160);
DISPLAY 0.659574 (-965 3160);
PAINT MONO (-965 3160);
DISPLAY INVISIBLE (-965 3160);
FORCEPROP 1 LASTPIN (-975 3150) BN 15
J 0
(-987 3158);
DISPLAY 0.680851 (-987 3158);
PAINT GREEN (-987 3158);
FORCEPROP 2 LAST CDS_LIB standard
J 0
(-925 3150);
PAINT MONO (-925 3150);
DISPLAY INVISIBLE (-925 3150);
FORCEPROP 1 LAST BODY_TYPE PLUMBING
J 0
(-925 3200);
DISPLAY 0.872340 (-925 3200);
PAINT GREEN (-925 3200);
DISPLAY INVISIBLE (-925 3200);
FORCEPROP 1 LAST HDL_TAP TRUE
J 0
(-600 3025);
DISPLAY 0.872340 (-600 3025);
DISPLAY INVISIBLE (-600 3025);
FORCEPROP 1 LAST PATH I94
J 0
(-927 3150);
DISPLAY 0.872340 (-927 3150);
PAINT GREEN (-927 3150);
DISPLAY INVISIBLE (-927 3150);
FORCEADD TAP..1
(-925 3100);
FORCEPROP 3 LASTPIN (-975 3100) SIG_NAME M_G_CPU1_SA_DQ<14>
J 0
(-965 3110);
DISPLAY 0.659574 (-965 3110);
PAINT MONO (-965 3110);
DISPLAY INVISIBLE (-965 3110);
FORCEPROP 1 LASTPIN (-975 3100) BN 14
J 0
(-987 3108);
DISPLAY 0.680851 (-987 3108);
PAINT GREEN (-987 3108);
FORCEPROP 2 LAST CDS_LIB standard
J 0
(-925 3100);
PAINT MONO (-925 3100);
DISPLAY INVISIBLE (-925 3100);
FORCEPROP 1 LAST BODY_TYPE PLUMBING
J 0
(-925 3150);
DISPLAY 0.872340 (-925 3150);
PAINT GREEN (-925 3150);
DISPLAY INVISIBLE (-925 3150);
FORCEPROP 1 LAST HDL_TAP TRUE
J 0
(-600 2975);
DISPLAY 0.872340 (-600 2975);
DISPLAY INVISIBLE (-600 2975);
FORCEPROP 1 LAST PATH I95
J 0
(-927 3100);
DISPLAY 0.872340 (-927 3100);
PAINT GREEN (-927 3100);
DISPLAY INVISIBLE (-927 3100);
FORCEADD TAP..1
(-925 3200);
FORCEPROP 3 LASTPIN (-975 3200) SIG_NAME M_G_CPU1_SA_DQ<16>
J 0
(-965 3210);
DISPLAY 0.659574 (-965 3210);
PAINT MONO (-965 3210);
DISPLAY INVISIBLE (-965 3210);
FORCEPROP 1 LASTPIN (-975 3200) BN 16
J 0
(-987 3208);
DISPLAY 0.680851 (-987 3208);
PAINT GREEN (-987 3208);
FORCEPROP 2 LAST CDS_LIB standard
J 0
(-925 3200);
PAINT MONO (-925 3200);
DISPLAY INVISIBLE (-925 3200);
FORCEPROP 1 LAST BODY_TYPE PLUMBING
J 0
(-925 3250);
DISPLAY 0.872340 (-925 3250);
PAINT GREEN (-925 3250);
DISPLAY INVISIBLE (-925 3250);
FORCEPROP 1 LAST HDL_TAP TRUE
J 0
(-600 3075);
DISPLAY 0.872340 (-600 3075);
DISPLAY INVISIBLE (-600 3075);
FORCEPROP 1 LAST PATH I96
J 0
(-927 3200);
DISPLAY 0.872340 (-927 3200);
PAINT GREEN (-927 3200);
DISPLAY INVISIBLE (-927 3200);
FORCEADD TAP..1
(-925 3300);
FORCEPROP 3 LASTPIN (-975 3300) SIG_NAME M_G_CPU1_SA_DQ<18>
J 0
(-965 3310);
DISPLAY 0.659574 (-965 3310);
PAINT MONO (-965 3310);
DISPLAY INVISIBLE (-965 3310);
FORCEPROP 1 LASTPIN (-975 3300) BN 18
J 0
(-987 3308);
DISPLAY 0.680851 (-987 3308);
PAINT GREEN (-987 3308);
FORCEPROP 2 LAST CDS_LIB standard
J 0
(-925 3300);
PAINT MONO (-925 3300);
DISPLAY INVISIBLE (-925 3300);
FORCEPROP 1 LAST BODY_TYPE PLUMBING
J 0
(-925 3350);
DISPLAY 0.872340 (-925 3350);
PAINT GREEN (-925 3350);
DISPLAY INVISIBLE (-925 3350);
FORCEPROP 1 LAST HDL_TAP TRUE
J 0
(-600 3175);
DISPLAY 0.872340 (-600 3175);
DISPLAY INVISIBLE (-600 3175);
FORCEPROP 1 LAST PATH I97
J 0
(-927 3300);
DISPLAY 0.872340 (-927 3300);
PAINT GREEN (-927 3300);
DISPLAY INVISIBLE (-927 3300);
FORCEADD TAP..1
(-925 3250);
FORCEPROP 3 LASTPIN (-975 3250) SIG_NAME M_G_CPU1_SA_DQ<17>
J 0
(-965 3260);
DISPLAY 0.659574 (-965 3260);
PAINT MONO (-965 3260);
DISPLAY INVISIBLE (-965 3260);
FORCEPROP 1 LASTPIN (-975 3250) BN 17
J 0
(-987 3258);
DISPLAY 0.680851 (-987 3258);
PAINT GREEN (-987 3258);
FORCEPROP 2 LAST CDS_LIB standard
J 0
(-925 3250);
PAINT MONO (-925 3250);
DISPLAY INVISIBLE (-925 3250);
FORCEPROP 1 LAST BODY_TYPE PLUMBING
J 0
(-925 3300);
DISPLAY 0.872340 (-925 3300);
PAINT GREEN (-925 3300);
DISPLAY INVISIBLE (-925 3300);
FORCEPROP 1 LAST HDL_TAP TRUE
J 0
(-600 3125);
DISPLAY 0.872340 (-600 3125);
DISPLAY INVISIBLE (-600 3125);
FORCEPROP 1 LAST PATH I98
J 0
(-927 3250);
DISPLAY 0.872340 (-927 3250);
PAINT GREEN (-927 3250);
DISPLAY INVISIBLE (-927 3250);
FORCEADD TAP..1
(-925 3350);
FORCEPROP 3 LASTPIN (-975 3350) SIG_NAME M_G_CPU1_SA_DQ<19>
J 0
(-965 3360);
DISPLAY 0.659574 (-965 3360);
PAINT MONO (-965 3360);
DISPLAY INVISIBLE (-965 3360);
FORCEPROP 1 LASTPIN (-975 3350) BN 19
J 0
(-987 3358);
DISPLAY 0.680851 (-987 3358);
PAINT GREEN (-987 3358);
FORCEPROP 2 LAST CDS_LIB standard
J 0
(-925 3350);
PAINT MONO (-925 3350);
DISPLAY INVISIBLE (-925 3350);
FORCEPROP 1 LAST BODY_TYPE PLUMBING
J 0
(-925 3400);
DISPLAY 0.872340 (-925 3400);
PAINT GREEN (-925 3400);
DISPLAY INVISIBLE (-925 3400);
FORCEPROP 1 LAST HDL_TAP TRUE
J 0
(-600 3225);
DISPLAY 0.872340 (-600 3225);
DISPLAY INVISIBLE (-600 3225);
FORCEPROP 1 LAST PATH I99
J 0
(-927 3350);
DISPLAY 0.872340 (-927 3350);
PAINT GREEN (-927 3350);
DISPLAY INVISIBLE (-927 3350);
FORCEADD CAD_NOTE..1
(925 -500);
FORCEPROP 0 LAST S1 PLACE THE BYPASS CAPS CLOSE TO DIMM
J 0
(800 -625);
DISPLAY 1.021277 (800 -625);
PAINT WHITE (800 -625);
FORCEPROP 2 LAST CDS_LIB logical_power
J 0
(925 -500);
PAINT MONO (925 -500);
DISPLAY INVISIBLE (925 -500);
FORCEPROP 1 LAST COMMENT_BODY TRUE
J 0
(950 -400);
DISPLAY 0.978723 (950 -400);
DISPLAY INVISIBLE (950 -400);
FORCEADD QUANTA_TITLE_BLOCK_C..1
(5400 -1800);
FORCEPROP 0 LAST CDS_CON_LAST_MODIFIED Fri Aug 25 14:01:31 2023
J 0
(3515 -1785);
PAINT MONO (3515 -1785);
DISPLAY INVISIBLE (3515 -1785);
FORCEPROP 2 LAST CUSTOM_TXT_CDS <XR_PAGE_TITLE>
J 0
(-2490 3450);
DISPLAY 0.638298 (-2490 3450);
PAINT PINK (-2490 3450);
DISPLAY INVISIBLE (-2490 3450);
FORCEPROP 2 LAST CUSTOM_TXT_CDS <NAME_1>
J 0
(2225 -1625);
FORCEPROP 2 LAST CUSTOM_TXT_CDS <NAME_2>
J 0
(2225 -1750);
FORCEPROP 2 LAST CUSTOM_TXT_CDS <Q_PROJ>
J 0
(3018 -1698);
DISPLAY 1.212766 (3018 -1698);
FORCEPROP 2 LAST CUSTOM_TXT_CDS <Q_NUMBER>
J 0
(3997 -1697);
DISPLAY 1.212766 (3997 -1697);
FORCEPROP 2 LAST CUSTOM_TXT_CDS <CON_LAST_MODIFIED>
J 0
(3515 -1785);
DISPLAY 0.978723 (3515 -1785);
FORCEPROP 2 LAST CUSTOM_TXT_CDS <Q_REV>
J 0
(5216 -1697);
DISPLAY 1.212766 (5216 -1697);
FORCEPROP 2 LAST CUSTOM_TXT_CDS <CON_PAGE_NUM> OF <CON_TOTAL_PAGES>
J 0
(4954 -1782);
DISPLAY 0.978723 (4954 -1782);
FORCEPROP 1 LAST Q_TITLE DDR5 - CPU1 CHG DIMM1(YELLOW)
J 0
(-3966 -1774);
DISPLAY 2.446809 (-3966 -1774);
PAINT GREEN (-3966 -1774);
FORCEPROP 1 LAST Q_DEPT 
J 1
(1637 -1751);
DISPLAY 1.957447 (1637 -1751);
PAINT GREEN (1637 -1751);
FORCEPROP 2 LAST CDS_XR_PAGE_TITLE CR-110 : @S9S_MB_2U_LIB.S9S_MB_2U(SCH_1):PAGE110
J 0
(-2490 3450);
DISPLAY 0.638298 (-2490 3450);
PAINT PINK (-2490 3450);
DISPLAY INVISIBLE (-2490 3450);
FORCEPROP 1 LAST COMMENT_BODY TRUE
J 0
(5412 -1813);
DISPLAY 0.978723 (5412 -1813);
PAINT GREEN (5412 -1813);
DISPLAY INVISIBLE (5412 -1813);
FORCEPROP 2 LAST PAGE_BORDER TRUE
J 0
(-2490 3450);
DISPLAY 0.638298 (-2490 3450);
PAINT PINK (-2490 3450);
DISPLAY INVISIBLE (-2490 3450);
FORCEPROP 1 LAST CDS_LMAN_SYM_OUTLINE -9475,6775,100,-125
J 0
(5400 -1800);
DISPLAY 0.468085 (5400 -1800);
PAINT GREEN (5400 -1800);
DISPLAY INVISIBLE (5400 -1800);
FORCEPROP 2 LAST CDS_LIB pure_quanta
J 0
(5400 -1800);
PAINT MONO (5400 -1800);
DISPLAY INVISIBLE (5400 -1800);
WIRE 17 -1 (-875 3975)(-150 3975);
FORCEPROP 2 LAST SIG_NAME M_G_CPU1_SA_DQ<31:0>
J 0
(-810 3985);
DISPLAY 0.680851 (-810 3985);
PAINT WHITE (-810 3985);
WIRE 17 -1 (-3450 2575)(-2625 2575);
FORCEPROP 2 LAST SIG_NAME M_G_CPU1_SA_CB<7:0>
J 0
(-3360 2585);
DISPLAY 0.680851 (-3360 2585);
PAINT WHITE (-3360 2585);
WIRE 17 -1 (-2625 2425)(-2625 2475);
WIRE 17 -1 (-2625 2375)(-2625 2425);
WIRE 17 -1 (-2625 2475)(-2625 2525);
WIRE 17 -1 (-2625 2525)(-2625 2575);
WIRE 17 -1 (-2625 2325)(-2625 2375);
WIRE 17 -1 (-2625 2275)(-2625 2325);
WIRE 17 -1 (-2625 2225)(-2625 2275);
WIRE 17 -1 (-3450 2125)(-2625 2125);
FORCEPROP 2 LAST SIG_NAME M_G_CPU1_SB_CB<7:0>
J 0
(-3360 2135);
DISPLAY 0.680851 (-3360 2135);
PAINT WHITE (-3360 2135);
WIRE 17 -1 (-2625 3675)(-2625 3725);
WIRE 17 -1 (-2625 3725)(-2625 3775);
WIRE 17 -1 (-2625 3775)(-2625 3825);
WIRE 17 -1 (-2625 3825)(-2625 3875);
WIRE 17 -1 (-2625 3875)(-2625 3925);
WIRE 17 -1 (-2625 3925)(-2625 3975);
WIRE 17 -1 (-3450 3975)(-2625 3975);
FORCEPROP 2 LAST SIG_NAME M_G_CPU1_SA_CA<6:0>
J 0
(-3360 3985);
DISPLAY 0.680851 (-3360 3985);
PAINT WHITE (-3360 3985);
WIRE 17 -1 (-2625 3275)(-2625 3325);
WIRE 17 -1 (-2625 3325)(-2625 3375);
WIRE 17 -1 (-2625 3375)(-2625 3425);
WIRE 17 -1 (-2625 3425)(-2625 3475);
WIRE 17 -1 (-2625 3475)(-2625 3525);
WIRE 17 -1 (-2625 3525)(-2625 3575);
WIRE 17 -1 (-3450 3575)(-2625 3575);
FORCEPROP 2 LAST SIG_NAME M_G_CPU1_SB_CA<6:0>
J 0
(-3360 3585);
DISPLAY 0.680851 (-3360 3585);
PAINT WHITE (-3360 3585);
WIRE 17 -1 (-2625 2025)(-2625 2075);
WIRE 17 -1 (-2625 1975)(-2625 2025);
WIRE 17 -1 (-2625 2075)(-2625 2125);
WIRE 17 -1 (-2625 1925)(-2625 1975);
WIRE 17 -1 (-2625 1875)(-2625 1925);
WIRE 17 -1 (-2625 1825)(-2625 1875);
WIRE 17 -1 (-2625 1775)(-2625 1825);
WIRE 17 -1 (-875 3925)(-875 3975);
WIRE 17 -1 (-875 3875)(-875 3925);
WIRE 17 -1 (-875 3825)(-875 3875);
WIRE 17 -1 (-875 3775)(-875 3825);
WIRE 17 -1 (-875 3725)(-875 3775);
WIRE 17 -1 (-875 3675)(-875 3725);
WIRE 17 -1 (-875 3625)(-875 3675);
WIRE 17 -1 (-875 3575)(-875 3625);
WIRE 17 -1 (-875 3525)(-875 3575);
WIRE 17 -1 (-875 3475)(-875 3525);
WIRE 17 -1 (-875 3425)(-875 3475);
WIRE 17 -1 (-875 3375)(-875 3425);
WIRE 17 -1 (-875 3325)(-875 3375);
WIRE 17 -1 (-875 3275)(-875 3325);
WIRE 17 -1 (-875 3225)(-875 3275);
WIRE 17 -1 (-875 3175)(-875 3225);
WIRE 17 -1 (-875 3125)(-875 3175);
WIRE 17 -1 (-875 3075)(-875 3125);
WIRE 17 -1 (-875 3025)(-875 3075);
WIRE 17 -1 (-875 2975)(-875 3025);
WIRE 17 -1 (-875 2925)(-875 2975);
WIRE 17 -1 (-875 2875)(-875 2925);
WIRE 17 -1 (-875 2825)(-875 2875);
WIRE 17 -1 (-875 2775)(-875 2825);
WIRE 17 -1 (-875 2725)(-875 2775);
WIRE 17 -1 (-875 2675)(-875 2725);
WIRE 17 -1 (-875 2625)(-875 2675);
WIRE 17 -1 (-875 2575)(-875 2625);
WIRE 17 -1 (-875 2525)(-875 2575);
WIRE 17 -1 (-875 2475)(-875 2525);
WIRE 17 -1 (-875 2425)(-875 2475);
WIRE 17 -1 (-875 2325)(-150 2325);
FORCEPROP 2 LAST SIG_NAME M_G_CPU1_SB_DQ<31:0>
J 0
(-810 2335);
DISPLAY 0.680851 (-810 2335);
PAINT WHITE (-810 2335);
WIRE 17 -1 (-875 2275)(-875 2325);
WIRE 17 -1 (-875 2225)(-875 2275);
WIRE 17 -1 (-875 2175)(-875 2225);
WIRE 17 -1 (-875 2125)(-875 2175);
WIRE 17 -1 (-875 2075)(-875 2125);
WIRE 17 -1 (-875 2025)(-875 2075);
WIRE 17 -1 (-875 1975)(-875 2025);
WIRE 17 -1 (-875 1925)(-875 1975);
WIRE 17 -1 (-875 1875)(-875 1925);
WIRE 17 -1 (-875 1825)(-875 1875);
WIRE 17 -1 (-875 1775)(-875 1825);
WIRE 17 -1 (-875 1725)(-875 1775);
WIRE 17 -1 (-875 1675)(-875 1725);
WIRE 17 -1 (-875 1625)(-875 1675);
WIRE 17 -1 (-875 1575)(-875 1625);
WIRE 17 -1 (-875 1525)(-875 1575);
WIRE 17 -1 (-875 1475)(-875 1525);
WIRE 17 -1 (-875 1425)(-875 1475);
WIRE 17 -1 (-875 1375)(-875 1425);
WIRE 17 -1 (-875 1325)(-875 1375);
WIRE 17 -1 (-875 1275)(-875 1325);
WIRE 17 -1 (-875 1225)(-875 1275);
WIRE 17 -1 (-875 1175)(-875 1225);
WIRE 17 -1 (-875 1125)(-875 1175);
WIRE 17 -1 (-875 1075)(-875 1125);
WIRE 17 -1 (-875 1025)(-875 1075);
WIRE 17 -1 (-875 975)(-875 1025);
WIRE 17 -1 (-875 925)(-875 975);
WIRE 17 -1 (-875 875)(-875 925);
WIRE 17 -1 (-875 825)(-875 875);
WIRE 17 -1 (-875 775)(-875 825);
WIRE 17 -1 (1875 2025)(1875 2125);
WIRE 17 -1 (1875 2125)(1875 2225);
WIRE 17 -1 (1875 2225)(1875 2325);
WIRE 17 -1 (1875 2425)(1875 2325);
WIRE 17 -1 (1875 2425)(1875 2525);
WIRE 17 -1 (1875 2525)(1875 2625);
WIRE 17 -1 (1875 2625)(1875 2725);
WIRE 17 -1 (1875 2725)(1875 2825);
WIRE 17 -1 (1875 2825)(1875 2925);
WIRE 17 -1 (1875 2925)(2900 2925);
FORCEPROP 2 LAST SIG_NAME M_G_CPU1_SB_DQS_DP<9:0>
J 0
(2115 2935);
DISPLAY 0.680851 (2115 2935);
PAINT WHITE (2115 2935);
WIRE 17 -1 (1875 3075)(1875 3175);
WIRE 17 -1 (1875 3175)(1875 3275);
WIRE 17 -1 (1875 3275)(1875 3375);
WIRE 17 -1 (1875 3475)(1875 3375);
WIRE 17 -1 (1875 3475)(1875 3575);
WIRE 17 -1 (1875 3575)(1875 3675);
WIRE 17 -1 (1875 3675)(1875 3775);
WIRE 17 -1 (1875 3775)(1875 3875);
WIRE 17 -1 (1875 3875)(1875 3975);
WIRE 17 -1 (1875 3975)(2900 3975);
FORCEPROP 2 LAST SIG_NAME M_G_CPU1_SA_DQS_DP<9:0>
J 0
(2115 3985);
DISPLAY 0.680851 (2115 3985);
PAINT WHITE (2115 3985);
WIRE 17 -1 (2050 1975)(2050 2075);
WIRE 17 -1 (2050 2075)(2050 2175);
WIRE 17 -1 (2050 2175)(2050 2275);
WIRE 17 -1 (2050 2375)(2050 2275);
WIRE 17 -1 (2050 2375)(2050 2475);
WIRE 17 -1 (2050 2475)(2050 2575);
WIRE 17 -1 (2050 2575)(2050 2675);
WIRE 17 -1 (2050 2675)(2050 2775);
WIRE 17 -1 (2050 2775)(2050 2875);
WIRE 17 -1 (2050 2875)(2900 2875);
FORCEPROP 2 LAST SIG_NAME M_G_CPU1_SB_DQS_DN<9:0>
J 0
(2115 2885);
DISPLAY 0.680851 (2115 2885);
PAINT WHITE (2115 2885);
WIRE 17 -1 (2050 3025)(2050 3125);
WIRE 17 -1 (2050 3125)(2050 3225);
WIRE 17 -1 (2050 3225)(2050 3325);
WIRE 17 -1 (2050 3425)(2050 3325);
WIRE 17 -1 (2050 3425)(2050 3525);
WIRE 17 -1 (2050 3525)(2050 3625);
WIRE 17 -1 (2050 3625)(2050 3725);
WIRE 17 -1 (2050 3725)(2050 3825);
WIRE 17 -1 (2050 3825)(2050 3925);
WIRE 17 -1 (2050 3925)(2900 3925);
FORCEPROP 2 LAST SIG_NAME M_G_CPU1_SA_DQS_DN<9:0>
J 0
(2115 3935);
DISPLAY 0.680851 (2115 3935);
PAINT WHITE (2115 3935);
WIRE 16 -1 (800 175)(800 350);
WIRE 16 -1 (1800 350)(1800 300);
WIRE 16 -1 (3500 4450)(3500 3950);
WIRE 16 -1 (-3400 1775)(-3400 1500);
WIRE 16 -1 (-2350 -375)(-2350 -300);
WIRE 16 -1 (800 -25)(800 -250);
WIRE 16 -1 (2425 -250)(2425 -175);
WIRE 16 -1 (3500 300)(3500 700);
WIRE 16 -1 (5200 600)(5200 300);
WIRE 16 -1 (5200 650)(5200 600);
WIRE 16 -1 (4950 600)(5200 600);
WIRE 16 -1 (-3400 1500)(-2350 1500);
WIRE 16 -1 (-2350 1400)(-3400 1400);
FORCEPROP 2 LAST SIG_NAME I3C_SPD_DDREFGH_CPU1_LVC1_SDA
J 0
(-3385 1410);
DISPLAY 0.680851 (-3385 1410);
PAINT WHITE (-3385 1410);
WIRE 16 -1 (-2350 1450)(-3400 1450);
FORCEPROP 2 LAST SIG_NAME PD_CHG_CPU1_DIMM1_SAA
J 0
(-3312 1459);
DISPLAY 0.680851 (-3312 1459);
PAINT WHITE (-3312 1459);
WIRE 16 -1 (-2350 1600)(-3425 1600);
FORCEPROP 2 LAST SIG_NAME M_G_CPU1_ALERT_N
J 0
(-3337 1609);
DISPLAY 0.680851 (-3337 1609);
PAINT WHITE (-3337 1609);
WIRE 16 -1 (-2625 1650)(-2350 1650);
WIRE 16 -1 (-2625 1725)(-3425 1725);
FORCEPROP 2 LAST SIG_NAME RST_M_GH_CPU1_FPGA_N
J 0
(-3337 1734);
DISPLAY 0.680851 (-3337 1734);
PAINT WHITE (-3337 1734);
WIRE 16 -1 (-2625 1725)(-2625 1650);
WIRE 16 -1 (-3875 1250)(-3675 1250);
WIRE 16 -1 (-3875 1250)(-3875 1350);
WIRE 16 -1 (-2350 1350)(-3875 1350);
FORCEPROP 2 LAST SIG_NAME I3C_SPD_DDREFGH_CPU1_LVC1_SCL_R5
J 0
(-3362 1359);
DISPLAY 0.680851 (-3362 1359);
PAINT WHITE (-3362 1359);
WIRE 16 -1 (-2250 1175)(-2275 1175);
WIRE 16 -1 (-2250 1250)(-2250 1175);
WIRE 16 -1 (-3475 1250)(-2250 1250);
FORCEPROP 2 LAST SIG_NAME I3C_SPD_DDREFGH_CPU1_LVC1_SCL
J 0
(-3260 1260);
DISPLAY 0.680851 (-3260 1260);
PAINT WHITE (-3260 1260);
WIRE 16 -1 (-2350 1100)(-3450 1100);
FORCEPROP 2 LAST SIG_NAME PWRGD_CHG_CPU1_DIMM1
J 0
(-3362 1109);
DISPLAY 0.680851 (-3362 1109);
PAINT WHITE (-3362 1109);
WIRE 16 -1 (-2350 1000)(-3450 1000);
FORCEPROP 2 LAST SIG_NAME TP_CHG_CPU1_DIMM1_FRU_6
J 0
(-3362 1009);
DISPLAY 0.680851 (-3362 1009);
PAINT WHITE (-3362 1009);
WIRE 16 -1 (-2525 1900)(-2350 1900);
WIRE 16 -1 (1675 2450)(1950 2450);
WIRE 16 -1 (1675 3900)(1950 3900);
WIRE 16 -1 (1675 3600)(1950 3600);
WIRE 16 -1 (1675 3800)(1950 3800);
WIRE 16 -1 (1675 3700)(1950 3700);
WIRE 16 -1 (1675 3500)(1950 3500);
WIRE 16 -1 (1675 3400)(1950 3400);
WIRE 16 -1 (1675 3300)(1950 3300);
WIRE 16 -1 (1675 3200)(1950 3200);
WIRE 16 -1 (1675 3100)(1950 3100);
WIRE 16 -1 (1675 2850)(1950 2850);
WIRE 16 -1 (1675 3000)(1950 3000);
WIRE 16 -1 (1675 2750)(1950 2750);
WIRE 16 -1 (1675 2650)(1950 2650);
WIRE 16 -1 (1675 2550)(1950 2550);
WIRE 16 -1 (1675 2350)(1950 2350);
WIRE 16 -1 (1675 2050)(1950 2050);
WIRE 16 -1 (1675 2250)(1950 2250);
WIRE 16 -1 (1675 2150)(1950 2150);
WIRE 16 -1 (1675 1950)(1950 1950);
WIRE 16 -1 (1675 3650)(1775 3650);
WIRE 16 -1 (1675 3750)(1775 3750);
WIRE 16 -1 (1675 3850)(1775 3850);
WIRE 16 -1 (1675 3950)(1775 3950);
WIRE 16 -1 (1675 3150)(1775 3150);
WIRE 16 -1 (1675 3250)(1775 3250);
WIRE 16 -1 (1675 3350)(1775 3350);
WIRE 16 -1 (1675 3450)(1775 3450);
WIRE 16 -1 (1675 3550)(1775 3550);
WIRE 16 -1 (1675 3050)(1775 3050);
WIRE 16 -1 (1675 2600)(1775 2600);
WIRE 16 -1 (1675 2700)(1775 2700);
WIRE 16 -1 (1675 2800)(1775 2800);
WIRE 16 -1 (1675 2900)(1775 2900);
WIRE 16 -1 (1675 2100)(1775 2100);
WIRE 16 -1 (1675 2200)(1775 2200);
WIRE 16 -1 (1675 2400)(1775 2400);
WIRE 16 -1 (1675 2300)(1775 2300);
WIRE 16 -1 (1675 2500)(1775 2500);
WIRE 16 -1 (1675 2000)(1775 2000);
WIRE 16 -1 (-2525 2050)(-2350 2050);
WIRE 16 -1 (-2350 750)(-3450 750);
FORCEPROP 2 LAST SIG_NAME TP_CHG_CPU1_DIMM1_FRU_1
J 0
(-3362 759);
DISPLAY 0.680851 (-3362 759);
PAINT WHITE (-3362 759);
WIRE 16 -1 (-2350 900)(-3450 900);
FORCEPROP 2 LAST SIG_NAME TP_CHG_CPU1_DIMM1_FRU_4
J 0
(-3362 909);
DISPLAY 0.680851 (-3362 909);
PAINT WHITE (-3362 909);
WIRE 16 -1 (-2350 950)(-3450 950);
FORCEPROP 2 LAST SIG_NAME TP_CHG_CPU1_DIMM1_FRU_5
J 0
(-3362 959);
DISPLAY 0.680851 (-3362 959);
PAINT WHITE (-3362 959);
WIRE 16 -1 (3750 3950)(3500 3950);
WIRE 16 -1 (3500 3950)(3500 3900);
WIRE 16 -1 (3500 3900)(3750 3900);
WIRE 16 -1 (3500 3900)(3500 3850);
WIRE 16 -1 (3750 3850)(3500 3850);
WIRE 16 -1 (-2350 2950)(-3450 2950);
FORCEPROP 2 LAST SIG_NAME M_G_CPU1_SA_CS_N<0>
J 0
(-3362 2959);
DISPLAY 0.680851 (-3362 2959);
PAINT WHITE (-3362 2959);
WIRE 16 -1 (-1150 2900)(-975 2900);
WIRE 16 -1 (-1150 2000)(-975 2000);
WIRE 16 -1 (-2350 700)(-3450 700);
FORCEPROP 2 LAST SIG_NAME TP_CHG_CPU1_DIMM1_FRU_0
J 0
(-3362 709);
DISPLAY 0.680851 (-3362 709);
PAINT WHITE (-3362 709);
WIRE 16 -1 (-2350 800)(-3450 800);
FORCEPROP 2 LAST SIG_NAME TP_CHG_CPU1_DIMM1_FRU_2
J 0
(-3362 809);
DISPLAY 0.680851 (-3362 809);
PAINT WHITE (-3362 809);
WIRE 16 -1 (-2350 850)(-3450 850);
FORCEPROP 2 LAST SIG_NAME TP_CHG_CPU1_DIMM1_FRU_3
J 0
(-3362 859);
DISPLAY 0.680851 (-3362 859);
PAINT WHITE (-3362 859);
WIRE 16 -1 (-2350 3100)(-3450 3100);
FORCEPROP 2 LAST SIG_NAME M_G_CPU1_SB_PAR
J 0
(-3362 3109);
DISPLAY 0.680851 (-3362 3109);
PAINT WHITE (-3362 3109);
WIRE 16 -1 (-2350 3150)(-3450 3150);
FORCEPROP 2 LAST SIG_NAME M_G_CPU1_SA_PAR
J 0
(-3362 3159);
DISPLAY 0.680851 (-3362 3159);
PAINT WHITE (-3362 3159);
WIRE 16 -1 (-2350 500)(-3450 500);
FORCEPROP 2 LAST SIG_NAME M_G_CPU1_SB_RSP<0>
J 0
(-3362 509);
DISPLAY 0.680851 (-3362 509);
PAINT WHITE (-3362 509);
WIRE 16 -1 (-2350 550)(-3450 550);
FORCEPROP 2 LAST SIG_NAME M_G_CPU1_SA_RSP<0>
J 0
(-3362 559);
DISPLAY 0.680851 (-3362 559);
PAINT WHITE (-3362 559);
WIRE 16 -1 (-1150 750)(-975 750);
WIRE 16 -1 (-1150 800)(-975 800);
WIRE 16 -1 (-1150 850)(-975 850);
WIRE 16 -1 (-1150 900)(-975 900);
WIRE 16 -1 (-1150 950)(-975 950);
WIRE 16 -1 (-1150 1000)(-975 1000);
WIRE 16 -1 (-1150 1050)(-975 1050);
WIRE 16 -1 (-1150 1100)(-975 1100);
WIRE 16 -1 (-1150 1150)(-975 1150);
WIRE 16 -1 (-1150 1200)(-975 1200);
WIRE 16 -1 (-1150 1250)(-975 1250);
WIRE 16 -1 (-1150 1300)(-975 1300);
WIRE 16 -1 (-1150 1350)(-975 1350);
WIRE 16 -1 (-1150 1400)(-975 1400);
WIRE 16 -1 (-1150 1450)(-975 1450);
WIRE 16 -1 (-1150 1500)(-975 1500);
WIRE 16 -1 (-1150 1550)(-975 1550);
WIRE 16 -1 (-1150 1600)(-975 1600);
WIRE 16 -1 (-1150 1650)(-975 1650);
WIRE 16 -1 (-1150 1700)(-975 1700);
WIRE 16 -1 (-1150 1750)(-975 1750);
WIRE 16 -1 (-1150 1800)(-975 1800);
WIRE 16 -1 (-1150 1850)(-975 1850);
WIRE 16 -1 (-1150 1900)(-975 1900);
WIRE 16 -1 (-1150 1950)(-975 1950);
WIRE 16 -1 (-1150 2050)(-975 2050);
WIRE 16 -1 (-1150 2100)(-975 2100);
WIRE 16 -1 (-1150 2150)(-975 2150);
WIRE 16 -1 (-1150 2200)(-975 2200);
WIRE 16 -1 (-1150 2250)(-975 2250);
WIRE 16 -1 (-1150 2300)(-975 2300);
WIRE 16 -1 (-1150 2400)(-975 2400);
WIRE 16 -1 (-1150 2450)(-975 2450);
WIRE 16 -1 (-1150 2500)(-975 2500);
WIRE 16 -1 (-1150 2550)(-975 2550);
WIRE 16 -1 (-1150 2600)(-975 2600);
WIRE 16 -1 (-1150 2650)(-975 2650);
WIRE 16 -1 (-1150 2700)(-975 2700);
WIRE 16 -1 (-1150 2750)(-975 2750);
WIRE 16 -1 (-1150 2800)(-975 2800);
WIRE 16 -1 (-1150 2850)(-975 2850);
WIRE 16 -1 (-1150 2950)(-975 2950);
WIRE 16 -1 (-1150 3000)(-975 3000);
WIRE 16 -1 (-1150 3050)(-975 3050);
WIRE 16 -1 (-1150 3100)(-975 3100);
WIRE 16 -1 (-1150 3150)(-975 3150);
WIRE 16 -1 (-1150 3200)(-975 3200);
WIRE 16 -1 (-1150 3250)(-975 3250);
WIRE 16 -1 (-1150 3300)(-975 3300);
WIRE 16 -1 (-1150 3350)(-975 3350);
WIRE 16 -1 (-1150 3400)(-975 3400);
WIRE 16 -1 (-1150 3450)(-975 3450);
WIRE 16 -1 (-1150 3500)(-975 3500);
WIRE 16 -1 (-1150 3550)(-975 3550);
WIRE 16 -1 (-1150 3600)(-975 3600);
WIRE 16 -1 (-1150 3650)(-975 3650);
WIRE 16 -1 (-1150 3700)(-975 3700);
WIRE 16 -1 (-1150 3750)(-975 3750);
WIRE 16 -1 (-1150 3800)(-975 3800);
WIRE 16 -1 (-1150 3850)(-975 3850);
WIRE 16 -1 (-1150 3900)(-975 3900);
WIRE 16 -1 (-2350 2850)(-3450 2850);
FORCEPROP 2 LAST SIG_NAME M_G_CPU1_SB_CS_N<1>
J 0
(-3362 2859);
DISPLAY 0.680851 (-3362 2859);
PAINT WHITE (-3362 2859);
WIRE 16 -1 (-2350 3000)(-3450 3000);
FORCEPROP 2 LAST SIG_NAME M_G_CPU1_SA_CS_N<1>
J 0
(-3362 3009);
DISPLAY 0.680851 (-3362 3009);
PAINT WHITE (-3362 3009);
WIRE 16 -1 (-2350 2800)(-3450 2800);
FORCEPROP 2 LAST SIG_NAME M_G_CPU1_SB_CS_N<0>
J 0
(-3362 2809);
DISPLAY 0.680851 (-3362 2809);
PAINT WHITE (-3362 2809);
WIRE 16 -1 (-2350 2700)(-3450 2700);
FORCEPROP 2 LAST SIG_NAME M_G_CPU1_CLK_DP<0>
J 0
(-3362 2709);
DISPLAY 0.680851 (-3362 2709);
PAINT WHITE (-3362 2709);
WIRE 16 -1 (-2350 2650)(-3450 2650);
FORCEPROP 2 LAST SIG_NAME M_G_CPU1_CLK_DN<0>
J 0
(-3362 2659);
DISPLAY 0.680851 (-3362 2659);
PAINT WHITE (-3362 2659);
WIRE 16 -1 (-2525 1750)(-2350 1750);
WIRE 16 -1 (-2525 1800)(-2350 1800);
WIRE 16 -1 (-2525 1850)(-2350 1850);
WIRE 16 -1 (-2525 1950)(-2350 1950);
WIRE 16 -1 (-2525 2000)(-2350 2000);
WIRE 16 -1 (-2525 2200)(-2350 2200);
WIRE 16 -1 (-2525 2300)(-2350 2300);
WIRE 16 -1 (-2525 2350)(-2350 2350);
WIRE 16 -1 (-2525 2450)(-2350 2450);
WIRE 16 -1 (-2525 2500)(-2350 2500);
WIRE 16 -1 (-2525 3550)(-2350 3550);
WIRE 16 -1 (-2525 3950)(-2350 3950);
WIRE 16 -1 (-2525 3500)(-2350 3500);
WIRE 16 -1 (-2525 3900)(-2350 3900);
WIRE 16 -1 (-2525 3450)(-2350 3450);
WIRE 16 -1 (-2525 3850)(-2350 3850);
WIRE 16 -1 (-2525 3400)(-2350 3400);
WIRE 16 -1 (-2525 3800)(-2350 3800);
WIRE 16 -1 (-2525 3350)(-2350 3350);
WIRE 16 -1 (-2525 3750)(-2350 3750);
WIRE 16 -1 (-2525 3300)(-2350 3300);
WIRE 16 -1 (-2525 3700)(-2350 3700);
WIRE 16 -1 (-2525 3250)(-2350 3250);
WIRE 16 -1 (-2525 3650)(-2350 3650);
WIRE 16 -1 (-2525 2100)(-2350 2100);
WIRE 16 -1 (-2525 2250)(-2350 2250);
WIRE 16 -1 (-2525 2400)(-2350 2400);
WIRE 16 -1 (-2525 2550)(-2350 2550);
WIRE 16 -1 (-1150 3950)(-975 3950);
WIRE 16 -1 (4950 3950)(5200 3950);
WIRE 16 -1 (4950 3900)(5200 3900);
WIRE 16 -1 (5200 3950)(5200 3900);
WIRE 16 -1 (4950 3850)(5200 3850);
WIRE 16 -1 (5200 3900)(5200 3850);
WIRE 16 -1 (4950 3800)(5200 3800);
WIRE 16 -1 (5200 3850)(5200 3800);
WIRE 16 -1 (4950 3750)(5200 3750);
WIRE 16 -1 (5200 3800)(5200 3750);
WIRE 16 -1 (4950 3700)(5200 3700);
WIRE 16 -1 (5200 3750)(5200 3700);
WIRE 16 -1 (4950 3650)(5200 3650);
WIRE 16 -1 (5200 3700)(5200 3650);
WIRE 16 -1 (4950 3600)(5200 3600);
WIRE 16 -1 (5200 3650)(5200 3600);
WIRE 16 -1 (4950 3550)(5200 3550);
WIRE 16 -1 (5200 3600)(5200 3550);
WIRE 16 -1 (4950 3500)(5200 3500);
WIRE 16 -1 (5200 3550)(5200 3500);
WIRE 16 -1 (4950 3450)(5200 3450);
WIRE 16 -1 (5200 3500)(5200 3450);
WIRE 16 -1 (4950 3400)(5200 3400);
WIRE 16 -1 (5200 3450)(5200 3400);
WIRE 16 -1 (4950 3350)(5200 3350);
WIRE 16 -1 (5200 3400)(5200 3350);
WIRE 16 -1 (4950 3300)(5200 3300);
WIRE 16 -1 (5200 3350)(5200 3300);
WIRE 16 -1 (4950 3250)(5200 3250);
WIRE 16 -1 (5200 3300)(5200 3250);
WIRE 16 -1 (4950 3200)(5200 3200);
WIRE 16 -1 (5200 3200)(5200 3250);
WIRE 16 -1 (4950 3150)(5200 3150);
WIRE 16 -1 (5200 3200)(5200 3150);
WIRE 16 -1 (5200 3100)(4950 3100);
WIRE 16 -1 (5200 3150)(5200 3100);
WIRE 16 -1 (5200 3050)(4950 3050);
WIRE 16 -1 (5200 3100)(5200 3050);
WIRE 16 -1 (4950 3000)(5200 3000);
WIRE 16 -1 (5200 3050)(5200 3000);
WIRE 16 -1 (4950 2950)(5200 2950);
WIRE 16 -1 (5200 3000)(5200 2950);
WIRE 16 -1 (4950 2900)(5200 2900);
WIRE 16 -1 (5200 2950)(5200 2900);
WIRE 16 -1 (4950 2850)(5200 2850);
WIRE 16 -1 (5200 2900)(5200 2850);
WIRE 16 -1 (4950 2800)(5200 2800);
WIRE 16 -1 (5200 2850)(5200 2800);
WIRE 16 -1 (4950 2750)(5200 2750);
WIRE 16 -1 (5200 2800)(5200 2750);
WIRE 16 -1 (4950 2700)(5200 2700);
WIRE 16 -1 (5200 2700)(5200 2750);
WIRE 16 -1 (4950 2650)(5200 2650);
WIRE 16 -1 (5200 2700)(5200 2650);
WIRE 16 -1 (5200 2600)(4950 2600);
WIRE 16 -1 (5200 2650)(5200 2600);
WIRE 16 -1 (5200 2550)(4950 2550);
WIRE 16 -1 (5200 2600)(5200 2550);
WIRE 16 -1 (4950 2500)(5200 2500);
WIRE 16 -1 (5200 2550)(5200 2500);
WIRE 16 -1 (4950 2450)(5200 2450);
WIRE 16 -1 (5200 2500)(5200 2450);
WIRE 16 -1 (4950 2400)(5200 2400);
WIRE 16 -1 (5200 2450)(5200 2400);
WIRE 16 -1 (4950 2350)(5200 2350);
WIRE 16 -1 (5200 2400)(5200 2350);
WIRE 16 -1 (4950 2300)(5200 2300);
WIRE 16 -1 (5200 2350)(5200 2300);
WIRE 16 -1 (4950 2250)(5200 2250);
WIRE 16 -1 (5200 2300)(5200 2250);
WIRE 16 -1 (4950 2200)(5200 2200);
WIRE 16 -1 (5200 2200)(5200 2250);
WIRE 16 -1 (4950 2150)(5200 2150);
WIRE 16 -1 (5200 2200)(5200 2150);
WIRE 16 -1 (5200 2100)(4950 2100);
WIRE 16 -1 (5200 2150)(5200 2100);
WIRE 16 -1 (5200 2050)(4950 2050);
WIRE 16 -1 (5200 2100)(5200 2050);
WIRE 16 -1 (4950 2000)(5200 2000);
WIRE 16 -1 (5200 2050)(5200 2000);
WIRE 16 -1 (4950 1950)(5200 1950);
WIRE 16 -1 (5200 2000)(5200 1950);
WIRE 16 -1 (4950 1900)(5200 1900);
WIRE 16 -1 (5200 1950)(5200 1900);
WIRE 16 -1 (4950 1850)(5200 1850);
WIRE 16 -1 (5200 1900)(5200 1850);
WIRE 16 -1 (4950 1800)(5200 1800);
WIRE 16 -1 (5200 1850)(5200 1800);
WIRE 16 -1 (4950 1750)(5200 1750);
WIRE 16 -1 (5200 1800)(5200 1750);
WIRE 16 -1 (4950 1700)(5200 1700);
WIRE 16 -1 (5200 1700)(5200 1750);
WIRE 16 -1 (4950 1650)(5200 1650);
WIRE 16 -1 (5200 1700)(5200 1650);
WIRE 16 -1 (5200 1600)(4950 1600);
WIRE 16 -1 (5200 1650)(5200 1600);
WIRE 16 -1 (5200 1550)(4950 1550);
WIRE 16 -1 (5200 1600)(5200 1550);
WIRE 16 -1 (5200 1500)(4950 1500);
WIRE 16 -1 (5200 1550)(5200 1500);
WIRE 16 -1 (5200 1450)(4950 1450);
WIRE 16 -1 (5200 1500)(5200 1450);
WIRE 16 -1 (4950 1400)(5200 1400);
WIRE 16 -1 (5200 1400)(5200 1450);
WIRE 16 -1 (5200 1350)(4950 1350);
WIRE 16 -1 (5200 1350)(5200 1400);
WIRE 16 -1 (5200 1300)(4950 1300);
WIRE 16 -1 (5200 1350)(5200 1300);
WIRE 16 -1 (5200 1250)(4950 1250);
WIRE 16 -1 (5200 1300)(5200 1250);
WIRE 16 -1 (4950 1200)(5200 1200);
WIRE 16 -1 (5200 1250)(5200 1200);
WIRE 16 -1 (4950 1150)(5200 1150);
WIRE 16 -1 (5200 1200)(5200 1150);
WIRE 16 -1 (4950 1100)(5200 1100);
WIRE 16 -1 (5200 1150)(5200 1100);
WIRE 16 -1 (4950 1050)(5200 1050);
WIRE 16 -1 (5200 1100)(5200 1050);
WIRE 16 -1 (4950 1000)(5200 1000);
WIRE 16 -1 (5200 1050)(5200 1000);
WIRE 16 -1 (4950 950)(5200 950);
WIRE 16 -1 (5200 1000)(5200 950);
WIRE 16 -1 (4950 900)(5200 900);
WIRE 16 -1 (5200 950)(5200 900);
WIRE 16 -1 (4950 850)(5200 850);
WIRE 16 -1 (5200 850)(5200 900);
WIRE 16 -1 (4950 800)(5200 800);
WIRE 16 -1 (5200 850)(5200 800);
WIRE 16 -1 (4950 700)(5200 700);
WIRE 16 -1 (5200 800)(5200 700);
WIRE 16 -1 (5200 700)(5200 650);
WIRE 16 -1 (4950 650)(5200 650);
WIRE 16 -1 (3750 3800)(3500 3800);
WIRE 16 -1 (3500 3750)(3500 3800);
WIRE 16 -1 (3500 3750)(3750 3750);
WIRE 16 -1 (3500 3700)(3500 3750);
WIRE 16 -1 (3750 3700)(3500 3700);
WIRE 16 -1 (3500 3650)(3500 3700);
WIRE 16 -1 (3500 3650)(3750 3650);
WIRE 16 -1 (3500 3600)(3500 3650);
WIRE 16 -1 (3500 3600)(3750 3600);
WIRE 16 -1 (3500 3550)(3500 3600);
WIRE 16 -1 (3500 3550)(3750 3550);
WIRE 16 -1 (3500 3500)(3500 3550);
WIRE 16 -1 (3500 3500)(3750 3500);
WIRE 16 -1 (3500 3450)(3500 3500);
WIRE 16 -1 (3500 3450)(3750 3450);
WIRE 16 -1 (3500 3400)(3500 3450);
WIRE 16 -1 (3500 3400)(3750 3400);
WIRE 16 -1 (3500 3350)(3500 3400);
WIRE 16 -1 (3500 3350)(3750 3350);
WIRE 16 -1 (3500 3300)(3500 3350);
WIRE 16 -1 (3500 3300)(3750 3300);
WIRE 16 -1 (3500 3250)(3500 3300);
WIRE 16 -1 (3500 3250)(3750 3250);
WIRE 16 -1 (3500 3200)(3500 3250);
WIRE 16 -1 (3750 3200)(3500 3200);
WIRE 16 -1 (3500 3150)(3500 3200);
WIRE 16 -1 (3500 3150)(3750 3150);
WIRE 16 -1 (3500 3100)(3500 3150);
WIRE 16 -1 (3500 3100)(3750 3100);
WIRE 16 -1 (3500 3050)(3750 3050);
WIRE 16 -1 (3500 3050)(3500 3100);
WIRE 16 -1 (3500 3000)(3500 3050);
WIRE 16 -1 (3500 3000)(3750 3000);
WIRE 16 -1 (3500 2950)(3500 3000);
WIRE 16 -1 (3500 2950)(3750 2950);
WIRE 16 -1 (3500 2900)(3500 2950);
WIRE 16 -1 (3500 2900)(3750 2900);
WIRE 16 -1 (3500 2850)(3500 2900);
WIRE 16 -1 (3500 2850)(3750 2850);
WIRE 16 -1 (3500 2800)(3500 2850);
WIRE 16 -1 (3500 2800)(3750 2800);
WIRE 16 -1 (3500 2750)(3500 2800);
WIRE 16 -1 (3500 2750)(3750 2750);
WIRE 16 -1 (3500 2700)(3500 2750);
WIRE 16 -1 (3750 2700)(3500 2700);
WIRE 16 -1 (3500 2650)(3500 2700);
WIRE 16 -1 (3500 2650)(3750 2650);
WIRE 16 -1 (3500 2600)(3500 2650);
WIRE 16 -1 (3500 2600)(3750 2600);
WIRE 16 -1 (3500 2550)(3500 2600);
WIRE 16 -1 (3500 2550)(3750 2550);
WIRE 16 -1 (3500 2500)(3500 2550);
WIRE 16 -1 (3500 2500)(3750 2500);
WIRE 16 -1 (3500 2450)(3500 2500);
WIRE 16 -1 (3500 2450)(3750 2450);
WIRE 16 -1 (3500 2400)(3500 2450);
WIRE 16 -1 (3500 2400)(3750 2400);
WIRE 16 -1 (3500 2350)(3500 2400);
WIRE 16 -1 (3500 2350)(3750 2350);
WIRE 16 -1 (3500 2300)(3500 2350);
WIRE 16 -1 (3500 2300)(3750 2300);
WIRE 16 -1 (3500 2250)(3500 2300);
WIRE 16 -1 (3500 2250)(3750 2250);
WIRE 16 -1 (3500 2200)(3500 2250);
WIRE 16 -1 (3750 2200)(3500 2200);
WIRE 16 -1 (3500 2150)(3500 2200);
WIRE 16 -1 (3500 2150)(3750 2150);
WIRE 16 -1 (3500 2100)(3500 2150);
WIRE 16 -1 (3500 2100)(3750 2100);
WIRE 16 -1 (3500 2050)(3500 2100);
WIRE 16 -1 (3500 2050)(3750 2050);
WIRE 16 -1 (3500 2000)(3750 2000);
WIRE 16 -1 (3500 2000)(3500 2050);
WIRE 16 -1 (3500 1950)(3500 2000);
WIRE 16 -1 (3500 1950)(3750 1950);
WIRE 16 -1 (3500 1900)(3500 1950);
WIRE 16 -1 (3500 1900)(3750 1900);
WIRE 16 -1 (3500 1850)(3500 1900);
WIRE 16 -1 (3500 1850)(3750 1850);
WIRE 16 -1 (3500 1800)(3500 1850);
WIRE 16 -1 (3500 1800)(3750 1800);
WIRE 16 -1 (3500 1750)(3500 1800);
WIRE 16 -1 (3500 1750)(3750 1750);
WIRE 16 -1 (3500 1700)(3500 1750);
WIRE 16 -1 (3750 1700)(3500 1700);
WIRE 16 -1 (3500 1650)(3500 1700);
WIRE 16 -1 (3500 1650)(3750 1650);
WIRE 16 -1 (3500 1600)(3500 1650);
WIRE 16 -1 (3500 1600)(3750 1600);
WIRE 16 -1 (3500 1550)(3500 1600);
WIRE 16 -1 (3500 1550)(3750 1550);
WIRE 16 -1 (3500 1500)(3500 1550);
WIRE 16 -1 (3500 1500)(3750 1500);
WIRE 16 -1 (3500 1450)(3500 1500);
WIRE 16 -1 (3500 1450)(3750 1450);
WIRE 16 -1 (3500 1400)(3500 1450);
WIRE 16 -1 (3500 1400)(3750 1400);
WIRE 16 -1 (3500 1350)(3500 1400);
WIRE 16 -1 (3500 1350)(3750 1350);
WIRE 16 -1 (3500 1300)(3500 1350);
WIRE 16 -1 (3500 1300)(3750 1300);
WIRE 16 -1 (3500 1250)(3500 1300);
WIRE 16 -1 (3500 1250)(3750 1250);
WIRE 16 -1 (3500 1200)(3500 1250);
WIRE 16 -1 (3750 1200)(3500 1200);
WIRE 16 -1 (3500 1150)(3500 1200);
WIRE 16 -1 (3500 1150)(3750 1150);
WIRE 16 -1 (3500 1100)(3500 1150);
WIRE 16 -1 (3500 1100)(3750 1100);
WIRE 16 -1 (3500 1050)(3500 1100);
WIRE 16 -1 (3500 1050)(3750 1050);
WIRE 16 -1 (3500 1000)(3750 1000);
WIRE 16 -1 (3500 1000)(3500 1050);
WIRE 16 -1 (3500 950)(3500 1000);
WIRE 16 -1 (3500 950)(3750 950);
WIRE 16 -1 (3500 900)(3500 950);
WIRE 16 -1 (3500 900)(3750 900);
WIRE 16 -1 (3500 850)(3500 900);
WIRE 16 -1 (3500 850)(3750 850);
WIRE 16 -1 (3500 800)(3500 850);
WIRE 16 -1 (3500 800)(3750 800);
WIRE 16 -1 (3500 750)(3500 800);
WIRE 16 -1 (3500 750)(3750 750);
WIRE 16 -1 (3500 700)(3500 750);
WIRE 16 -1 (3500 700)(3750 700);
WIRE 16 3135 (450 575)(450 -725);
WIRE 16 3135 (3050 575)(450 575);
WIRE 16 3135 (450 -725)(3050 -725);
WIRE 16 3135 (3050 -725)(3050 575);
WIRE 16 -1 (1800 -175)(1800 -25);
WIRE 16 -1 (2425 -175)(1800 -175);
WIRE 16 -1 (2425 -175)(2425 -25);
WIRE 16 -1 (1800 300)(1800 175);
WIRE 16 -1 (2425 300)(1800 300);
WIRE 16 -1 (2425 175)(2425 300);
WIRE 16 -1 (-2350 0)(-3450 0);
FORCEPROP 2 LAST SIG_NAME PD_CHG_CPU1_DIMM1_SAA
J 0
(-3362 9);
DISPLAY 0.680851 (-3362 9);
PAINT WHITE (-3362 9);
WIRE 16 -1 (-2350 -100)(-2350 0);
DOT 1 (3500 3300);
DOT 1 (3500 2600);
DOT 1 (5200 3900);
DOT 1 (5200 3850);
DOT 1 (5200 3800);
DOT 1 (5200 3750);
DOT 1 (5200 3700);
DOT 1 (5200 3650);
DOT 1 (5200 3600);
DOT 1 (5200 3550);
DOT 1 (5200 3500);
DOT 1 (5200 3450);
DOT 1 (5200 3400);
DOT 1 (5200 3350);
DOT 1 (5200 3300);
DOT 1 (5200 3250);
DOT 1 (5200 3200);
DOT 1 (5200 3150);
DOT 1 (5200 3100);
DOT 1 (5200 3050);
DOT 1 (5200 3000);
DOT 1 (5200 2950);
DOT 1 (5200 2900);
DOT 1 (5200 2850);
DOT 1 (5200 2800);
DOT 1 (5200 2750);
DOT 1 (5200 2700);
DOT 1 (5200 2600);
DOT 1 (5200 2650);
DOT 1 (5200 2550);
DOT 1 (5200 2500);
DOT 1 (5200 2450);
DOT 1 (5200 2400);
DOT 1 (5200 2350);
DOT 1 (5200 2300);
DOT 1 (5200 2250);
DOT 1 (5200 2200);
DOT 1 (5200 2150);
DOT 1 (5200 2100);
DOT 1 (5200 2050);
DOT 1 (5200 2000);
DOT 1 (5200 1950);
DOT 1 (5200 1900);
DOT 1 (5200 1850);
DOT 1 (5200 1800);
DOT 1 (5200 1750);
DOT 1 (5200 1700);
DOT 1 (5200 1650);
DOT 1 (5200 1600);
DOT 1 (5200 1550);
DOT 1 (5200 1500);
DOT 1 (5200 1450);
DOT 1 (5200 1400);
DOT 1 (5200 1350);
DOT 1 (5200 1300);
DOT 1 (5200 1250);
DOT 1 (5200 1200);
DOT 1 (5200 1150);
DOT 1 (5200 1100);
DOT 1 (5200 1050);
DOT 1 (5200 1000);
DOT 1 (5200 950);
DOT 1 (5200 900);
DOT 1 (5200 850);
DOT 1 (5200 800);
DOT 1 (3500 3950);
DOT 1 (3500 3900);
DOT 1 (3500 3750);
DOT 1 (3500 3700);
DOT 1 (3500 3650);
DOT 1 (3500 3600);
DOT 1 (3500 3500);
DOT 1 (3500 3550);
DOT 1 (3500 3450);
DOT 1 (3500 3400);
DOT 1 (3500 3350);
DOT 1 (3500 3250);
DOT 1 (3500 3200);
DOT 1 (3500 3150);
DOT 1 (3500 3100);
DOT 1 (3500 3050);
DOT 1 (3500 3000);
DOT 1 (3500 2950);
DOT 1 (3500 2900);
DOT 1 (3500 2850);
DOT 1 (3500 2800);
DOT 1 (3500 2750);
DOT 1 (3500 2700);
DOT 1 (3500 2650);
DOT 1 (3500 2550);
DOT 1 (3500 2500);
DOT 1 (3500 2450);
DOT 1 (3500 2350);
DOT 1 (3500 2400);
DOT 1 (3500 2300);
DOT 1 (3500 2250);
DOT 1 (3500 2200);
DOT 1 (3500 2150);
DOT 1 (3500 2100);
DOT 1 (3500 2050);
DOT 1 (3500 2000);
DOT 1 (3500 1950);
DOT 1 (3500 1900);
DOT 1 (3500 1850);
DOT 1 (3500 1800);
DOT 1 (3500 1700);
DOT 1 (3500 1750);
DOT 1 (3500 1650);
DOT 1 (3500 1600);
DOT 1 (3500 1550);
DOT 1 (3500 1450);
DOT 1 (3500 1500);
DOT 1 (3500 1400);
DOT 1 (3500 1350);
DOT 1 (3500 1300);
DOT 1 (3500 1250);
DOT 1 (3500 1200);
DOT 1 (3500 1150);
DOT 1 (3500 1100);
DOT 1 (3500 1050);
DOT 1 (3500 1000);
DOT 1 (3500 950);
DOT 1 (3500 900);
DOT 1 (3500 850);
DOT 1 (3500 800);
DOT 1 (3500 750);
DOT 1 (3500 700);
DOT 1 (1800 300);
DOT 1 (2425 -175);
DOT 1 (5200 700);
DOT 1 (5200 650);
DOT 1 (5200 600);
FORCENOTE
20210728 MODIFY FOR GT
(-3800 4600) 0;
DISPLAY LEFT (-3800 4600);
DISPLAY 2.510638 (-3800 4600);
PAINT PINK (-3800 4600);
QUIT
